(kicad_sch
	(version 20250114)
	(generator "eeschema")
	(generator_version "9.0")
	(paper "A3")
	(title_block
		(title "PolarFire SoM")
		(date "2025-07-22")
		(rev "1.1.4")
		(company "Antmicro Ltd")
		(comment 1 "www.antmicro.com")
	)
	(text "MSS CLK"
		(exclude_from_sim no)
		(at 86.36 147.32 0)
		(effects
			(font
				(size 4 4)
				(thickness 0.8)
				(bold yes)
			)
			(justify left bottom)
		)
	)
	(text "PolarFire Bank 6\nMSS_DDR"
		(exclude_from_sim no)
		(at 212.725 27.305 0)
		(effects
			(font
				(size 4 4)
				(thickness 0.8)
				(bold yes)
			)
			(justify left bottom)
		)
	)
	(text "PolarFire Bank 5 \nMSS_SGMII"
		(exclude_from_sim no)
		(at 15.24 27.305 0)
		(effects
			(font
				(size 4 4)
				(thickness 0.8)
				(bold yes)
			)
			(justify left bottom)
		)
	)
	(junction
		(at 341.63 214.63)
		(diameter 0)
		(color 0 0 0 0)
	)
	(junction
		(at 78.74 161.29)
		(diameter 0)
		(color 0 0 0 0)
	)
	(junction
		(at 78.74 168.91)
		(diameter 0)
		(color 0 0 0 0)
	)
	(junction
		(at 87.63 162.56)
		(diameter 0)
		(color 0 0 0 0)
	)
	(no_connect
		(at 74.93 107.95)
	)
	(no_connect
		(at 336.55 148.59)
	)
	(no_connect
		(at 273.05 214.63)
	)
	(no_connect
		(at 336.55 209.55)
	)
	(no_connect
		(at 273.05 209.55)
	)
	(no_connect
		(at 336.55 102.87)
	)
	(no_connect
		(at 336.55 191.77)
	)
	(no_connect
		(at 336.55 97.79)
	)
	(no_connect
		(at 336.55 110.49)
	)
	(no_connect
		(at 336.55 156.21)
	)
	(no_connect
		(at 273.05 212.09)
	)
	(no_connect
		(at 336.55 153.67)
	)
	(no_connect
		(at 74.93 100.33)
	)
	(no_connect
		(at 336.55 105.41)
	)
	(no_connect
		(at 273.05 199.39)
	)
	(no_connect
		(at 336.55 204.47)
	)
	(no_connect
		(at 336.55 201.93)
	)
	(no_connect
		(at 336.55 92.71)
	)
	(no_connect
		(at 273.05 201.93)
	)
	(no_connect
		(at 336.55 115.57)
	)
	(no_connect
		(at 336.55 95.25)
	)
	(no_connect
		(at 336.55 140.97)
	)
	(no_connect
		(at 336.55 146.05)
	)
	(no_connect
		(at 273.05 207.01)
	)
	(no_connect
		(at 336.55 158.75)
	)
	(no_connect
		(at 336.55 113.03)
	)
	(no_connect
		(at 336.55 212.09)
	)
	(no_connect
		(at 336.55 107.95)
	)
	(no_connect
		(at 74.93 102.87)
	)
	(no_connect
		(at 273.05 204.47)
	)
	(no_connect
		(at 336.55 199.39)
	)
	(no_connect
		(at 74.93 110.49)
	)
	(no_connect
		(at 336.55 151.13)
	)
	(no_connect
		(at 336.55 100.33)
	)
	(no_connect
		(at 336.55 118.11)
	)
	(bus_entry
		(at 252.73 120.65)
		(size 2.54 2.54)
		(stroke
			(width 0)
			(type default)
		)
	)
	(bus_entry
		(at 252.73 176.53)
		(size 2.54 2.54)
		(stroke
			(width 0)
			(type default)
		)
	)
	(bus_entry
		(at 359.41 80.01)
		(size -2.54 2.54)
		(stroke
			(width 0)
			(type default)
		)
	)
	(bus_entry
		(at 359.41 74.93)
		(size -2.54 2.54)
		(stroke
			(width 0)
			(type default)
		)
	)
	(bus_entry
		(at 252.73 191.77)
		(size 2.54 2.54)
		(stroke
			(width 0)
			(type default)
		)
	)
	(bus_entry
		(at 359.41 140.97)
		(size -2.54 2.54)
		(stroke
			(width 0)
			(type default)
		)
	)
	(bus_entry
		(at 137.16 105.41)
		(size -2.54 2.54)
		(stroke
			(width 0)
			(type default)
		)
	)
	(bus_entry
		(at 359.41 77.47)
		(size -2.54 2.54)
		(stroke
			(width 0)
			(type default)
		)
	)
	(bus_entry
		(at 252.73 128.27)
		(size 2.54 2.54)
		(stroke
			(width 0)
			(type default)
		)
	)
	(bus_entry
		(at 252.73 85.09)
		(size 2.54 2.54)
		(stroke
			(width 0)
			(type default)
		)
	)
	(bus_entry
		(at 252.73 161.29)
		(size 2.54 2.54)
		(stroke
			(width 0)
			(type default)
		)
	)
	(bus_entry
		(at 252.73 173.99)
		(size 2.54 2.54)
		(stroke
			(width 0)
			(type default)
		)
	)
	(bus_entry
		(at 359.41 191.77)
		(size -2.54 2.54)
		(stroke
			(width 0)
			(type default)
		)
	)
	(bus_entry
		(at 137.16 100.33)
		(size -2.54 2.54)
		(stroke
			(width 0)
			(type default)
		)
	)
	(bus_entry
		(at 252.73 181.61)
		(size 2.54 2.54)
		(stroke
			(width 0)
			(type default)
		)
	)
	(bus_entry
		(at 252.73 95.25)
		(size 2.54 2.54)
		(stroke
			(width 0)
			(type default)
		)
	)
	(bus_entry
		(at 252.73 153.67)
		(size 2.54 2.54)
		(stroke
			(width 0)
			(type default)
		)
	)
	(bus_entry
		(at 252.73 97.79)
		(size 2.54 2.54)
		(stroke
			(width 0)
			(type default)
		)
	)
	(bus_entry
		(at 252.73 135.89)
		(size 2.54 2.54)
		(stroke
			(width 0)
			(type default)
		)
	)
	(bus_entry
		(at 252.73 82.55)
		(size 2.54 2.54)
		(stroke
			(width 0)
			(type default)
		)
	)
	(bus_entry
		(at 252.73 146.05)
		(size 2.54 2.54)
		(stroke
			(width 0)
			(type default)
		)
	)
	(bus_entry
		(at 252.73 92.71)
		(size 2.54 2.54)
		(stroke
			(width 0)
			(type default)
		)
	)
	(bus_entry
		(at 252.73 140.97)
		(size 2.54 2.54)
		(stroke
			(width 0)
			(type default)
		)
	)
	(bus_entry
		(at 252.73 138.43)
		(size 2.54 2.54)
		(stroke
			(width 0)
			(type default)
		)
	)
	(bus_entry
		(at 252.73 87.63)
		(size 2.54 2.54)
		(stroke
			(width 0)
			(type default)
		)
	)
	(bus_entry
		(at 359.41 194.31)
		(size -2.54 2.54)
		(stroke
			(width 0)
			(type default)
		)
	)
	(bus_entry
		(at 137.16 97.79)
		(size -2.54 2.54)
		(stroke
			(width 0)
			(type default)
		)
	)
	(bus_entry
		(at 252.73 186.69)
		(size 2.54 2.54)
		(stroke
			(width 0)
			(type default)
		)
	)
	(bus_entry
		(at 252.73 143.51)
		(size 2.54 2.54)
		(stroke
			(width 0)
			(type default)
		)
	)
	(bus_entry
		(at 252.73 123.19)
		(size 2.54 2.54)
		(stroke
			(width 0)
			(type default)
		)
	)
	(bus_entry
		(at 252.73 107.95)
		(size 2.54 2.54)
		(stroke
			(width 0)
			(type default)
		)
	)
	(bus_entry
		(at 252.73 189.23)
		(size 2.54 2.54)
		(stroke
			(width 0)
			(type default)
		)
	)
	(bus_entry
		(at 359.41 85.09)
		(size -2.54 2.54)
		(stroke
			(width 0)
			(type default)
		)
	)
	(bus_entry
		(at 252.73 130.81)
		(size 2.54 2.54)
		(stroke
			(width 0)
			(type default)
		)
	)
	(bus_entry
		(at 252.73 171.45)
		(size 2.54 2.54)
		(stroke
			(width 0)
			(type default)
		)
	)
	(bus_entry
		(at 252.73 168.91)
		(size 2.54 2.54)
		(stroke
			(width 0)
			(type default)
		)
	)
	(bus_entry
		(at 252.73 105.41)
		(size 2.54 2.54)
		(stroke
			(width 0)
			(type default)
		)
	)
	(bus_entry
		(at 252.73 125.73)
		(size 2.54 2.54)
		(stroke
			(width 0)
			(type default)
		)
	)
	(bus_entry
		(at 252.73 80.01)
		(size 2.54 2.54)
		(stroke
			(width 0)
			(type default)
		)
	)
	(bus_entry
		(at 137.16 107.95)
		(size -2.54 2.54)
		(stroke
			(width 0)
			(type default)
		)
	)
	(bus_entry
		(at 252.73 90.17)
		(size 2.54 2.54)
		(stroke
			(width 0)
			(type default)
		)
	)
	(bus_entry
		(at 252.73 151.13)
		(size 2.54 2.54)
		(stroke
			(width 0)
			(type default)
		)
	)
	(bus_entry
		(at 252.73 179.07)
		(size 2.54 2.54)
		(stroke
			(width 0)
			(type default)
		)
	)
	(bus_entry
		(at 252.73 77.47)
		(size 2.54 2.54)
		(stroke
			(width 0)
			(type default)
		)
	)
	(bus_entry
		(at 359.41 87.63)
		(size -2.54 2.54)
		(stroke
			(width 0)
			(type default)
		)
	)
	(bus_entry
		(at 252.73 118.11)
		(size 2.54 2.54)
		(stroke
			(width 0)
			(type default)
		)
	)
	(bus_entry
		(at 252.73 156.21)
		(size 2.54 2.54)
		(stroke
			(width 0)
			(type default)
		)
	)
	(bus_entry
		(at 252.73 74.93)
		(size 2.54 2.54)
		(stroke
			(width 0)
			(type default)
		)
	)
	(bus_entry
		(at 359.41 133.35)
		(size -2.54 2.54)
		(stroke
			(width 0)
			(type default)
		)
	)
	(bus_entry
		(at 252.73 100.33)
		(size 2.54 2.54)
		(stroke
			(width 0)
			(type default)
		)
	)
	(bus_entry
		(at 252.73 113.03)
		(size 2.54 2.54)
		(stroke
			(width 0)
			(type default)
		)
	)
	(bus_entry
		(at 252.73 115.57)
		(size 2.54 2.54)
		(stroke
			(width 0)
			(type default)
		)
	)
	(bus_entry
		(at 252.73 184.15)
		(size 2.54 2.54)
		(stroke
			(width 0)
			(type default)
		)
	)
	(bus_entry
		(at 252.73 110.49)
		(size 2.54 2.54)
		(stroke
			(width 0)
			(type default)
		)
	)
	(bus_entry
		(at 359.41 204.47)
		(size -2.54 2.54)
		(stroke
			(width 0)
			(type default)
		)
	)
	(bus_entry
		(at 252.73 158.75)
		(size 2.54 2.54)
		(stroke
			(width 0)
			(type default)
		)
	)
	(bus_entry
		(at 359.41 135.89)
		(size -2.54 2.54)
		(stroke
			(width 0)
			(type default)
		)
	)
	(bus_entry
		(at 252.73 166.37)
		(size 2.54 2.54)
		(stroke
			(width 0)
			(type default)
		)
	)
	(bus_entry
		(at 252.73 148.59)
		(size 2.54 2.54)
		(stroke
			(width 0)
			(type default)
		)
	)
	(bus_entry
		(at 359.41 82.55)
		(size -2.54 2.54)
		(stroke
			(width 0)
			(type default)
		)
	)
	(bus
		(pts
			(xy 252.73 130.81) (xy 252.73 135.89)
		)
		(stroke
			(width 0)
			(type default)
		)
	)
	(bus
		(pts
			(xy 252.73 158.75) (xy 252.73 161.29)
		)
		(stroke
			(width 0)
			(type default)
		)
	)
	(wire
		(pts
			(xy 273.05 125.73) (xy 255.27 125.73)
		)
		(stroke
			(width 0)
			(type default)
		)
	)
	(bus
		(pts
			(xy 250.19 72.39) (xy 251.46 72.39)
		)
		(stroke
			(width 0)
			(type default)
		)
	)
	(wire
		(pts
			(xy 125.73 162.56) (xy 128.27 162.56)
		)
		(stroke
			(width 0)
			(type default)
		)
	)
	(wire
		(pts
			(xy 356.87 90.17) (xy 336.55 90.17)
		)
		(stroke
			(width 0)
			(type default)
		)
	)
	(wire
		(pts
			(xy 255.27 90.17) (xy 273.05 90.17)
		)
		(stroke
			(width 0)
			(type default)
		)
	)
	(wire
		(pts
			(xy 255.27 128.27) (xy 273.05 128.27)
		)
		(stroke
			(width 0)
			(type default)
		)
	)
	(bus
		(pts
			(xy 252.73 146.05) (xy 252.73 148.59)
		)
		(stroke
			(width 0)
			(type default)
		)
	)
	(bus
		(pts
			(xy 252.73 97.79) (xy 252.73 100.33)
		)
		(stroke
			(width 0)
			(type default)
		)
	)
	(wire
		(pts
			(xy 273.05 179.07) (xy 255.27 179.07)
		)
		(stroke
			(width 0)
			(type default)
		)
	)
	(wire
		(pts
			(xy 273.05 173.99) (xy 255.27 173.99)
		)
		(stroke
			(width 0)
			(type default)
		)
	)
	(bus
		(pts
			(xy 252.73 100.33) (xy 252.73 105.41)
		)
		(stroke
			(width 0)
			(type default)
		)
	)
	(wire
		(pts
			(xy 255.27 189.23) (xy 273.05 189.23)
		)
		(stroke
			(width 0)
			(type default)
		)
	)
	(wire
		(pts
			(xy 107.95 162.56) (xy 120.65 162.56)
		)
		(stroke
			(width 0)
			(type default)
		)
	)
	(wire
		(pts
			(xy 255.27 95.25) (xy 273.05 95.25)
		)
		(stroke
			(width 0)
			(type default)
		)
	)
	(bus
		(pts
			(xy 252.73 125.73) (xy 252.73 128.27)
		)
		(stroke
			(width 0)
			(type default)
		)
	)
	(wire
		(pts
			(xy 273.05 113.03) (xy 255.27 113.03)
		)
		(stroke
			(width 0)
			(type default)
		)
	)
	(bus
		(pts
			(xy 252.73 105.41) (xy 252.73 107.95)
		)
		(stroke
			(width 0)
			(type default)
		)
	)
	(wire
		(pts
			(xy 255.27 82.55) (xy 273.05 82.55)
		)
		(stroke
			(width 0)
			(type default)
		)
	)
	(bus
		(pts
			(xy 251.46 72.39) (xy 252.73 73.66)
		)
		(stroke
			(width 0)
			(type default)
		)
	)
	(bus
		(pts
			(xy 252.73 138.43) (xy 252.73 140.97)
		)
		(stroke
			(width 0)
			(type default)
		)
	)
	(bus
		(pts
			(xy 252.73 153.67) (xy 252.73 156.21)
		)
		(stroke
			(width 0)
			(type default)
		)
	)
	(bus
		(pts
			(xy 359.41 77.47) (xy 359.41 80.01)
		)
		(stroke
			(width 0)
			(type default)
		)
	)
	(wire
		(pts
			(xy 273.05 184.15) (xy 255.27 184.15)
		)
		(stroke
			(width 0)
			(type default)
		)
	)
	(wire
		(pts
			(xy 78.74 161.29) (xy 78.74 162.56)
		)
		(stroke
			(width 0)
			(type default)
		)
	)
	(bus
		(pts
			(xy 359.41 73.66) (xy 359.41 74.93)
		)
		(stroke
			(width 0)
			(type default)
		)
	)
	(wire
		(pts
			(xy 255.27 158.75) (xy 273.05 158.75)
		)
		(stroke
			(width 0)
			(type default)
		)
	)
	(wire
		(pts
			(xy 273.05 107.95) (xy 255.27 107.95)
		)
		(stroke
			(width 0)
			(type default)
		)
	)
	(bus
		(pts
			(xy 252.73 161.29) (xy 252.73 166.37)
		)
		(stroke
			(width 0)
			(type default)
		)
	)
	(wire
		(pts
			(xy 120.65 107.95) (xy 134.62 107.95)
		)
		(stroke
			(width 0)
			(type default)
		)
	)
	(bus
		(pts
			(xy 252.73 171.45) (xy 252.73 173.99)
		)
		(stroke
			(width 0)
			(type default)
		)
	)
	(bus
		(pts
			(xy 252.73 151.13) (xy 252.73 153.67)
		)
		(stroke
			(width 0)
			(type default)
		)
	)
	(wire
		(pts
			(xy 78.74 168.91) (xy 78.74 170.18)
		)
		(stroke
			(width 0)
			(type default)
		)
	)
	(wire
		(pts
			(xy 273.05 153.67) (xy 255.27 153.67)
		)
		(stroke
			(width 0)
			(type default)
		)
	)
	(wire
		(pts
			(xy 356.87 80.01) (xy 336.55 80.01)
		)
		(stroke
			(width 0)
			(type default)
		)
	)
	(bus
		(pts
			(xy 360.68 72.39) (xy 359.41 73.66)
		)
		(stroke
			(width 0)
			(type default)
		)
	)
	(wire
		(pts
			(xy 336.55 138.43) (xy 356.87 138.43)
		)
		(stroke
			(width 0)
			(type default)
		)
	)
	(wire
		(pts
			(xy 341.63 218.44) (xy 341.63 214.63)
		)
		(stroke
			(width 0)
			(type default)
		)
	)
	(bus
		(pts
			(xy 137.16 100.33) (xy 137.16 105.41)
		)
		(stroke
			(width 0)
			(type default)
		)
	)
	(wire
		(pts
			(xy 336.55 207.01) (xy 356.87 207.01)
		)
		(stroke
			(width 0)
			(type default)
		)
	)
	(wire
		(pts
			(xy 273.05 140.97) (xy 255.27 140.97)
		)
		(stroke
			(width 0)
			(type default)
		)
	)
	(wire
		(pts
			(xy 356.87 77.47) (xy 336.55 77.47)
		)
		(stroke
			(width 0)
			(type default)
		)
	)
	(wire
		(pts
			(xy 341.63 214.63) (xy 345.44 214.63)
		)
		(stroke
			(width 0)
			(type default)
		)
	)
	(bus
		(pts
			(xy 359.41 133.35) (xy 359.41 135.89)
		)
		(stroke
			(width 0)
			(type default)
		)
	)
	(bus
		(pts
			(xy 252.73 128.27) (xy 252.73 130.81)
		)
		(stroke
			(width 0)
			(type default)
		)
	)
	(bus
		(pts
			(xy 252.73 176.53) (xy 252.73 179.07)
		)
		(stroke
			(width 0)
			(type default)
		)
	)
	(bus
		(pts
			(xy 252.73 115.57) (xy 252.73 118.11)
		)
		(stroke
			(width 0)
			(type default)
		)
	)
	(wire
		(pts
			(xy 273.05 168.91) (xy 255.27 168.91)
		)
		(stroke
			(width 0)
			(type default)
		)
	)
	(wire
		(pts
			(xy 356.87 87.63) (xy 336.55 87.63)
		)
		(stroke
			(width 0)
			(type default)
		)
	)
	(bus
		(pts
			(xy 252.73 118.11) (xy 252.73 120.65)
		)
		(stroke
			(width 0)
			(type default)
		)
	)
	(wire
		(pts
			(xy 336.55 194.31) (xy 356.87 194.31)
		)
		(stroke
			(width 0)
			(type default)
		)
	)
	(wire
		(pts
			(xy 356.87 85.09) (xy 336.55 85.09)
		)
		(stroke
			(width 0)
			(type default)
		)
	)
	(wire
		(pts
			(xy 255.27 191.77) (xy 273.05 191.77)
		)
		(stroke
			(width 0)
			(type default)
		)
	)
	(bus
		(pts
			(xy 252.73 123.19) (xy 252.73 125.73)
		)
		(stroke
			(width 0)
			(type default)
		)
	)
	(bus
		(pts
			(xy 252.73 73.66) (xy 252.73 74.93)
		)
		(stroke
			(width 0)
			(type default)
		)
	)
	(wire
		(pts
			(xy 273.05 176.53) (xy 255.27 176.53)
		)
		(stroke
			(width 0)
			(type default)
		)
	)
	(wire
		(pts
			(xy 255.27 80.01) (xy 273.05 80.01)
		)
		(stroke
			(width 0)
			(type default)
		)
	)
	(bus
		(pts
			(xy 252.73 181.61) (xy 252.73 184.15)
		)
		(stroke
			(width 0)
			(type default)
		)
	)
	(bus
		(pts
			(xy 252.73 107.95) (xy 252.73 110.49)
		)
		(stroke
			(width 0)
			(type default)
		)
	)
	(bus
		(pts
			(xy 252.73 120.65) (xy 252.73 123.19)
		)
		(stroke
			(width 0)
			(type default)
		)
	)
	(wire
		(pts
			(xy 255.27 92.71) (xy 273.05 92.71)
		)
		(stroke
			(width 0)
			(type default)
		)
	)
	(bus
		(pts
			(xy 359.41 140.97) (xy 359.41 191.77)
		)
		(stroke
			(width 0)
			(type default)
		)
	)
	(wire
		(pts
			(xy 273.05 118.11) (xy 255.27 118.11)
		)
		(stroke
			(width 0)
			(type default)
		)
	)
	(bus
		(pts
			(xy 252.73 80.01) (xy 252.73 82.55)
		)
		(stroke
			(width 0)
			(type default)
		)
	)
	(wire
		(pts
			(xy 88.9 167.64) (xy 87.63 167.64)
		)
		(stroke
			(width 0)
			(type default)
		)
	)
	(wire
		(pts
			(xy 273.05 163.83) (xy 255.27 163.83)
		)
		(stroke
			(width 0)
			(type default)
		)
	)
	(wire
		(pts
			(xy 78.74 167.64) (xy 78.74 168.91)
		)
		(stroke
			(width 0)
			(type default)
		)
	)
	(wire
		(pts
			(xy 350.52 218.44) (xy 356.87 218.44)
		)
		(stroke
			(width 0)
			(type default)
		)
	)
	(wire
		(pts
			(xy 78.74 160.02) (xy 78.74 161.29)
		)
		(stroke
			(width 0)
			(type default)
		)
	)
	(wire
		(pts
			(xy 273.05 148.59) (xy 255.27 148.59)
		)
		(stroke
			(width 0)
			(type default)
		)
	)
	(wire
		(pts
			(xy 273.05 138.43) (xy 255.27 138.43)
		)
		(stroke
			(width 0)
			(type default)
		)
	)
	(wire
		(pts
			(xy 336.55 214.63) (xy 341.63 214.63)
		)
		(stroke
			(width 0)
			(type default)
		)
	)
	(bus
		(pts
			(xy 252.73 156.21) (xy 252.73 158.75)
		)
		(stroke
			(width 0)
			(type default)
		)
	)
	(bus
		(pts
			(xy 137.16 97.79) (xy 137.16 100.33)
		)
		(stroke
			(width 0)
			(type default)
		)
	)
	(bus
		(pts
			(xy 137.16 96.52) (xy 137.16 97.79)
		)
		(stroke
			(width 0)
			(type default)
		)
	)
	(bus
		(pts
			(xy 252.73 85.09) (xy 252.73 87.63)
		)
		(stroke
			(width 0)
			(type default)
		)
	)
	(bus
		(pts
			(xy 252.73 110.49) (xy 252.73 113.03)
		)
		(stroke
			(width 0)
			(type default)
		)
	)
	(wire
		(pts
			(xy 255.27 161.29) (xy 273.05 161.29)
		)
		(stroke
			(width 0)
			(type default)
		)
	)
	(wire
		(pts
			(xy 273.05 115.57) (xy 255.27 115.57)
		)
		(stroke
			(width 0)
			(type default)
		)
	)
	(bus
		(pts
			(xy 252.73 82.55) (xy 252.73 85.09)
		)
		(stroke
			(width 0)
			(type default)
		)
	)
	(bus
		(pts
			(xy 252.73 166.37) (xy 252.73 168.91)
		)
		(stroke
			(width 0)
			(type default)
		)
	)
	(bus
		(pts
			(xy 252.73 179.07) (xy 252.73 181.61)
		)
		(stroke
			(width 0)
			(type default)
		)
	)
	(bus
		(pts
			(xy 359.41 135.89) (xy 359.41 140.97)
		)
		(stroke
			(width 0)
			(type default)
		)
	)
	(bus
		(pts
			(xy 252.73 77.47) (xy 252.73 80.01)
		)
		(stroke
			(width 0)
			(type default)
		)
	)
	(bus
		(pts
			(xy 359.41 85.09) (xy 359.41 87.63)
		)
		(stroke
			(width 0)
			(type default)
		)
	)
	(wire
		(pts
			(xy 273.05 171.45) (xy 255.27 171.45)
		)
		(stroke
			(width 0)
			(type default)
		)
	)
	(bus
		(pts
			(xy 137.16 105.41) (xy 137.16 107.95)
		)
		(stroke
			(width 0)
			(type default)
		)
	)
	(wire
		(pts
			(xy 255.27 102.87) (xy 273.05 102.87)
		)
		(stroke
			(width 0)
			(type default)
		)
	)
	(bus
		(pts
			(xy 139.7 95.25) (xy 138.43 95.25)
		)
		(stroke
			(width 0)
			(type default)
		)
	)
	(bus
		(pts
			(xy 359.41 87.63) (xy 359.41 133.35)
		)
		(stroke
			(width 0)
			(type default)
		)
	)
	(wire
		(pts
			(xy 273.05 194.31) (xy 255.27 194.31)
		)
		(stroke
			(width 0)
			(type default)
		)
	)
	(bus
		(pts
			(xy 252.73 184.15) (xy 252.73 186.69)
		)
		(stroke
			(width 0)
			(type default)
		)
	)
	(wire
		(pts
			(xy 87.63 165.1) (xy 87.63 162.56)
		)
		(stroke
			(width 0)
			(type default)
		)
	)
	(bus
		(pts
			(xy 252.73 95.25) (xy 252.73 97.79)
		)
		(stroke
			(width 0)
			(type default)
		)
	)
	(wire
		(pts
			(xy 255.27 77.47) (xy 273.05 77.47)
		)
		(stroke
			(width 0)
			(type default)
		)
	)
	(wire
		(pts
			(xy 356.87 82.55) (xy 336.55 82.55)
		)
		(stroke
			(width 0)
			(type default)
		)
	)
	(wire
		(pts
			(xy 273.05 186.69) (xy 255.27 186.69)
		)
		(stroke
			(width 0)
			(type default)
		)
	)
	(wire
		(pts
			(xy 273.05 100.33) (xy 255.27 100.33)
		)
		(stroke
			(width 0)
			(type default)
		)
	)
	(wire
		(pts
			(xy 78.74 168.91) (xy 87.63 168.91)
		)
		(stroke
			(width 0)
			(type default)
		)
	)
	(bus
		(pts
			(xy 252.73 92.71) (xy 252.73 95.25)
		)
		(stroke
			(width 0)
			(type default)
		)
	)
	(wire
		(pts
			(xy 273.05 146.05) (xy 255.27 146.05)
		)
		(stroke
			(width 0)
			(type default)
		)
	)
	(bus
		(pts
			(xy 252.73 148.59) (xy 252.73 151.13)
		)
		(stroke
			(width 0)
			(type default)
		)
	)
	(wire
		(pts
			(xy 88.9 165.1) (xy 87.63 165.1)
		)
		(stroke
			(width 0)
			(type default)
		)
	)
	(bus
		(pts
			(xy 252.73 140.97) (xy 252.73 143.51)
		)
		(stroke
			(width 0)
			(type default)
		)
	)
	(wire
		(pts
			(xy 87.63 167.64) (xy 87.63 168.91)
		)
		(stroke
			(width 0)
			(type default)
		)
	)
	(wire
		(pts
			(xy 273.05 151.13) (xy 255.27 151.13)
		)
		(stroke
			(width 0)
			(type default)
		)
	)
	(bus
		(pts
			(xy 252.73 90.17) (xy 252.73 92.71)
		)
		(stroke
			(width 0)
			(type default)
		)
	)
	(bus
		(pts
			(xy 252.73 113.03) (xy 252.73 115.57)
		)
		(stroke
			(width 0)
			(type default)
		)
	)
	(wire
		(pts
			(xy 273.05 181.61) (xy 255.27 181.61)
		)
		(stroke
			(width 0)
			(type default)
		)
	)
	(wire
		(pts
			(xy 273.05 156.21) (xy 255.27 156.21)
		)
		(stroke
			(width 0)
			(type default)
		)
	)
	(wire
		(pts
			(xy 255.27 130.81) (xy 273.05 130.81)
		)
		(stroke
			(width 0)
			(type default)
		)
	)
	(wire
		(pts
			(xy 273.05 133.35) (xy 255.27 133.35)
		)
		(stroke
			(width 0)
			(type default)
		)
	)
	(wire
		(pts
			(xy 336.55 135.89) (xy 356.87 135.89)
		)
		(stroke
			(width 0)
			(type default)
		)
	)
	(wire
		(pts
			(xy 273.05 123.19) (xy 255.27 123.19)
		)
		(stroke
			(width 0)
			(type default)
		)
	)
	(wire
		(pts
			(xy 78.74 161.29) (xy 87.63 161.29)
		)
		(stroke
			(width 0)
			(type default)
		)
	)
	(wire
		(pts
			(xy 273.05 97.79) (xy 255.27 97.79)
		)
		(stroke
			(width 0)
			(type default)
		)
	)
	(wire
		(pts
			(xy 336.55 196.85) (xy 356.87 196.85)
		)
		(stroke
			(width 0)
			(type default)
		)
	)
	(bus
		(pts
			(xy 252.73 189.23) (xy 252.73 191.77)
		)
		(stroke
			(width 0)
			(type default)
		)
	)
	(bus
		(pts
			(xy 359.41 80.01) (xy 359.41 82.55)
		)
		(stroke
			(width 0)
			(type default)
		)
	)
	(wire
		(pts
			(xy 120.65 118.11) (xy 125.73 118.11)
		)
		(stroke
			(width 0)
			(type default)
		)
	)
	(wire
		(pts
			(xy 87.63 161.29) (xy 87.63 162.56)
		)
		(stroke
			(width 0)
			(type default)
		)
	)
	(wire
		(pts
			(xy 120.65 100.33) (xy 134.62 100.33)
		)
		(stroke
			(width 0)
			(type default)
		)
	)
	(wire
		(pts
			(xy 120.65 115.57) (xy 125.73 115.57)
		)
		(stroke
			(width 0)
			(type default)
		)
	)
	(bus
		(pts
			(xy 359.41 191.77) (xy 359.41 194.31)
		)
		(stroke
			(width 0)
			(type default)
		)
	)
	(wire
		(pts
			(xy 107.95 165.1) (xy 120.65 165.1)
		)
		(stroke
			(width 0)
			(type default)
		)
	)
	(bus
		(pts
			(xy 252.73 135.89) (xy 252.73 138.43)
		)
		(stroke
			(width 0)
			(type default)
		)
	)
	(bus
		(pts
			(xy 359.41 82.55) (xy 359.41 85.09)
		)
		(stroke
			(width 0)
			(type default)
		)
	)
	(bus
		(pts
			(xy 252.73 74.93) (xy 252.73 77.47)
		)
		(stroke
			(width 0)
			(type default)
		)
	)
	(wire
		(pts
			(xy 273.05 143.51) (xy 255.27 143.51)
		)
		(stroke
			(width 0)
			(type default)
		)
	)
	(bus
		(pts
			(xy 252.73 168.91) (xy 252.73 171.45)
		)
		(stroke
			(width 0)
			(type default)
		)
	)
	(bus
		(pts
			(xy 252.73 87.63) (xy 252.73 90.17)
		)
		(stroke
			(width 0)
			(type default)
		)
	)
	(polyline
		(pts
			(xy 210.185 13.335) (xy 210.185 283.845)
		)
		(stroke
			(width 0)
			(type dash)
		)
	)
	(wire
		(pts
			(xy 273.05 120.65) (xy 255.27 120.65)
		)
		(stroke
			(width 0)
			(type default)
		)
	)
	(wire
		(pts
			(xy 336.55 143.51) (xy 356.87 143.51)
		)
		(stroke
			(width 0)
			(type default)
		)
	)
	(bus
		(pts
			(xy 138.43 95.25) (xy 137.16 96.52)
		)
		(stroke
			(width 0)
			(type default)
		)
	)
	(bus
		(pts
			(xy 359.41 74.93) (xy 359.41 77.47)
		)
		(stroke
			(width 0)
			(type default)
		)
	)
	(wire
		(pts
			(xy 350.52 214.63) (xy 356.87 214.63)
		)
		(stroke
			(width 0)
			(type default)
		)
	)
	(bus
		(pts
			(xy 252.73 186.69) (xy 252.73 189.23)
		)
		(stroke
			(width 0)
			(type default)
		)
	)
	(bus
		(pts
			(xy 252.73 173.99) (xy 252.73 176.53)
		)
		(stroke
			(width 0)
			(type default)
		)
	)
	(bus
		(pts
			(xy 252.73 143.51) (xy 252.73 146.05)
		)
		(stroke
			(width 0)
			(type default)
		)
	)
	(wire
		(pts
			(xy 345.44 218.44) (xy 341.63 218.44)
		)
		(stroke
			(width 0)
			(type default)
		)
	)
	(wire
		(pts
			(xy 255.27 85.09) (xy 273.05 85.09)
		)
		(stroke
			(width 0)
			(type default)
		)
	)
	(wire
		(pts
			(xy 120.65 110.49) (xy 134.62 110.49)
		)
		(stroke
			(width 0)
			(type default)
		)
	)
	(wire
		(pts
			(xy 87.63 162.56) (xy 88.9 162.56)
		)
		(stroke
			(width 0)
			(type default)
		)
	)
	(wire
		(pts
			(xy 255.27 87.63) (xy 273.05 87.63)
		)
		(stroke
			(width 0)
			(type default)
		)
	)
	(bus
		(pts
			(xy 359.41 194.31) (xy 359.41 204.47)
		)
		(stroke
			(width 0)
			(type default)
		)
	)
	(wire
		(pts
			(xy 125.73 165.1) (xy 128.27 165.1)
		)
		(stroke
			(width 0)
			(type default)
		)
	)
	(bus
		(pts
			(xy 361.95 72.39) (xy 360.68 72.39)
		)
		(stroke
			(width 0)
			(type default)
		)
	)
	(wire
		(pts
			(xy 120.65 102.87) (xy 134.62 102.87)
		)
		(stroke
			(width 0)
			(type default)
		)
	)
	(wire
		(pts
			(xy 273.05 110.49) (xy 255.27 110.49)
		)
		(stroke
			(width 0)
			(type default)
		)
	)
	(label "LPDDR4.DMI3"
		(at 255.27 194.31 0)
		(effects
			(font
				(size 1.27 1.27)
			)
			(justify left bottom)
		)
	)
	(label "LPDDR4.DQS0_P"
		(at 255.27 97.79 0)
		(effects
			(font
				(size 1.27 1.27)
			)
			(justify left bottom)
		)
	)
	(label "LPDDR4.DMI2"
		(at 255.27 163.83 0)
		(effects
			(font
				(size 1.27 1.27)
			)
			(justify left bottom)
		)
	)
	(label "MSS_CLK_N"
		(at 108.585 165.1 0)
		(effects
			(font
				(size 1.27 1.27)
			)
			(justify left bottom)
		)
	)
	(label "LPDDR4.DQS1_P"
		(at 255.27 128.27 0)
		(effects
			(font
				(size 1.27 1.27)
			)
			(justify left bottom)
		)
	)
	(label "LPDDR4.DQ5"
		(at 255.27 90.17 0)
		(effects
			(font
				(size 1.27 1.27)
			)
			(justify left bottom)
		)
	)
	(label "LPDDR4.CA5_A"
		(at 356.87 90.17 180)
		(effects
			(font
				(size 1.27 1.27)
			)
			(justify right bottom)
		)
	)
	(label "LPDDR4.CA3_A"
		(at 356.87 85.09 180)
		(effects
			(font
				(size 1.27 1.27)
			)
			(justify right bottom)
		)
	)
	(label "LPDDR4.DQS2_P"
		(at 255.27 158.75 0)
		(effects
			(font
				(size 1.27 1.27)
			)
			(justify left bottom)
		)
	)
	(label "LPDDR4.ODT_CA_A"
		(at 356.87 207.01 180)
		(effects
			(font
				(size 1.27 1.27)
			)
			(justify right bottom)
		)
	)
	(label "SGMII.TX0_P"
		(at 134.62 100.33 180)
		(effects
			(font
				(size 1.27 1.27)
			)
			(justify right bottom)
		)
	)
	(label "LPDDR4.CA2_A"
		(at 356.87 82.55 180)
		(effects
			(font
				(size 1.27 1.27)
			)
			(justify right bottom)
		)
	)
	(label "LPDDR4.DQ15"
		(at 255.27 125.73 0)
		(effects
			(font
				(size 1.27 1.27)
			)
			(justify left bottom)
		)
	)
	(label "LPDDR4.DQ1"
		(at 255.27 80.01 0)
		(effects
			(font
				(size 1.27 1.27)
			)
			(justify left bottom)
		)
	)
	(label "LPDDR4.DQ11"
		(at 255.27 115.57 0)
		(effects
			(font
				(size 1.27 1.27)
			)
			(justify left bottom)
		)
	)
	(label "LPDDR4.CK_N"
		(at 356.87 196.85 180)
		(effects
			(font
				(size 1.27 1.27)
			)
			(justify right bottom)
		)
	)
	(label "LPDDR4.CKE0_A"
		(at 356.87 143.51 180)
		(effects
			(font
				(size 1.27 1.27)
			)
			(justify right bottom)
		)
	)
	(label "LPDDR4.DQ17"
		(at 255.27 140.97 0)
		(effects
			(font
				(size 1.27 1.27)
			)
			(justify left bottom)
		)
	)
	(label "LPDDR4.DQ18"
		(at 255.27 143.51 0)
		(effects
			(font
				(size 1.27 1.27)
			)
			(justify left bottom)
		)
	)
	(label "LPDDR4.DQ28"
		(at 255.27 179.07 0)
		(effects
			(font
				(size 1.27 1.27)
			)
			(justify left bottom)
		)
	)
	(label "LPDDR4.DQ12"
		(at 255.27 118.11 0)
		(effects
			(font
				(size 1.27 1.27)
			)
			(justify left bottom)
		)
	)
	(label "LPDDR4.DQ7"
		(at 255.27 95.25 0)
		(effects
			(font
				(size 1.27 1.27)
			)
			(justify left bottom)
		)
	)
	(label "LPDDR4.DQ23"
		(at 255.27 156.21 0)
		(effects
			(font
				(size 1.27 1.27)
			)
			(justify left bottom)
		)
	)
	(label "LPDDR4.DQS2_N"
		(at 255.27 161.29 0)
		(effects
			(font
				(size 1.27 1.27)
			)
			(justify left bottom)
		)
	)
	(label "LPDDR4.DQ8"
		(at 255.27 107.95 0)
		(effects
			(font
				(size 1.27 1.27)
			)
			(justify left bottom)
		)
	)
	(label "LPDDR4.DQS3_N"
		(at 255.27 191.77 0)
		(effects
			(font
				(size 1.27 1.27)
			)
			(justify left bottom)
		)
	)
	(label "LPDDR4.CK_P"
		(at 356.87 194.31 180)
		(effects
			(font
				(size 1.27 1.27)
			)
			(justify right bottom)
		)
	)
	(label "LPDDR4.DQ4"
		(at 255.27 87.63 0)
		(effects
			(font
				(size 1.27 1.27)
			)
			(justify left bottom)
		)
	)
	(label "LPDDR4.DQ25"
		(at 255.27 171.45 0)
		(effects
			(font
				(size 1.27 1.27)
			)
			(justify left bottom)
		)
	)
	(label "LPDDR4.DQ27"
		(at 255.27 176.53 0)
		(effects
			(font
				(size 1.27 1.27)
			)
			(justify left bottom)
		)
	)
	(label "LPDDR4.DQ29"
		(at 255.27 181.61 0)
		(effects
			(font
				(size 1.27 1.27)
			)
			(justify left bottom)
		)
	)
	(label "LPDDR4.DQS1_N"
		(at 255.27 130.81 0)
		(effects
			(font
				(size 1.27 1.27)
			)
			(justify left bottom)
		)
	)
	(label "LPDDR4.DQ20"
		(at 255.27 148.59 0)
		(effects
			(font
				(size 1.27 1.27)
			)
			(justify left bottom)
		)
	)
	(label "LPDDR4.DQ30"
		(at 255.27 184.15 0)
		(effects
			(font
				(size 1.27 1.27)
			)
			(justify left bottom)
		)
	)
	(label "MSS_CLK_P"
		(at 108.585 162.56 0)
		(effects
			(font
				(size 1.27 1.27)
			)
			(justify left bottom)
		)
	)
	(label "LPDDR4.DQ16"
		(at 255.27 138.43 0)
		(effects
			(font
				(size 1.27 1.27)
			)
			(justify left bottom)
		)
	)
	(label "LPDDR4.RESET_n"
		(at 356.87 135.89 180)
		(effects
			(font
				(size 1.27 1.27)
			)
			(justify right bottom)
		)
	)
	(label "SGMII.RX0_P"
		(at 134.62 107.95 180)
		(effects
			(font
				(size 1.27 1.27)
			)
			(justify right bottom)
		)
	)
	(label "LPDDR4.DQ22"
		(at 255.27 153.67 0)
		(effects
			(font
				(size 1.27 1.27)
			)
			(justify left bottom)
		)
	)
	(label "LPDDR4.DQ0"
		(at 255.27 77.47 0)
		(effects
			(font
				(size 1.27 1.27)
			)
			(justify left bottom)
		)
	)
	(label "LPDDR4.DQ10"
		(at 255.27 113.03 0)
		(effects
			(font
				(size 1.27 1.27)
			)
			(justify left bottom)
		)
	)
	(label "LPDDR4.DQS3_P"
		(at 255.27 189.23 0)
		(effects
			(font
				(size 1.27 1.27)
			)
			(justify left bottom)
		)
	)
	(label "LPDDR4.DQ9"
		(at 255.27 110.49 0)
		(effects
			(font
				(size 1.27 1.27)
			)
			(justify left bottom)
		)
	)
	(label "LPDDR4.DQ13"
		(at 255.27 120.65 0)
		(effects
			(font
				(size 1.27 1.27)
			)
			(justify left bottom)
		)
	)
	(label "LPDDR4.CS0_A"
		(at 356.87 138.43 180)
		(effects
			(font
				(size 1.27 1.27)
			)
			(justify right bottom)
		)
	)
	(label "SGMII.TX0_N"
		(at 134.62 102.87 180)
		(effects
			(font
				(size 1.27 1.27)
			)
			(justify right bottom)
		)
	)
	(label "LPDDR4.DMI0"
		(at 255.27 102.87 0)
		(effects
			(font
				(size 1.27 1.27)
			)
			(justify left bottom)
		)
	)
	(label "SGMII.RX0_N"
		(at 134.62 110.49 180)
		(effects
			(font
				(size 1.27 1.27)
			)
			(justify right bottom)
		)
	)
	(label "LPDDR4.DQ21"
		(at 255.27 151.13 0)
		(effects
			(font
				(size 1.27 1.27)
			)
			(justify left bottom)
		)
	)
	(label "LPDDR4.DQ3"
		(at 255.27 85.09 0)
		(effects
			(font
				(size 1.27 1.27)
			)
			(justify left bottom)
		)
	)
	(label "LPDDR4.DQ31"
		(at 255.27 186.69 0)
		(effects
			(font
				(size 1.27 1.27)
			)
			(justify left bottom)
		)
	)
	(label "LPDDR4.DQ19"
		(at 255.27 146.05 0)
		(effects
			(font
				(size 1.27 1.27)
			)
			(justify left bottom)
		)
	)
	(label "LPDDR4.CA0_A"
		(at 356.87 77.47 180)
		(effects
			(font
				(size 1.27 1.27)
			)
			(justify right bottom)
		)
	)
	(label "LPDDR4.DQ6"
		(at 255.27 92.71 0)
		(effects
			(font
				(size 1.27 1.27)
			)
			(justify left bottom)
		)
	)
	(label "LPDDR4.DQ2"
		(at 255.27 82.55 0)
		(effects
			(font
				(size 1.27 1.27)
			)
			(justify left bottom)
		)
	)
	(label "LPDDR4.DQS0_N"
		(at 255.27 100.33 0)
		(effects
			(font
				(size 1.27 1.27)
			)
			(justify left bottom)
		)
	)
	(label "LPDDR4.DQ24"
		(at 255.27 168.91 0)
		(effects
			(font
				(size 1.27 1.27)
			)
			(justify left bottom)
		)
	)
	(label "LPDDR4.DMI1"
		(at 255.27 133.35 0)
		(effects
			(font
				(size 1.27 1.27)
			)
			(justify left bottom)
		)
	)
	(label "LPDDR4.DQ14"
		(at 255.27 123.19 0)
		(effects
			(font
				(size 1.27 1.27)
			)
			(justify left bottom)
		)
	)
	(label "LPDDR4.CA4_A"
		(at 356.87 87.63 180)
		(effects
			(font
				(size 1.27 1.27)
			)
			(justify right bottom)
		)
	)
	(label "LPDDR4.DQ26"
		(at 255.27 173.99 0)
		(effects
			(font
				(size 1.27 1.27)
			)
			(justify left bottom)
		)
	)
	(label "LPDDR4.CA1_A"
		(at 356.87 80.01 180)
		(effects
			(font
				(size 1.27 1.27)
			)
			(justify right bottom)
		)
	)
	(global_label "MSS_REFCLK_N"
		(shape input)
		(at 128.27 165.1 0)
		(fields_autoplaced yes)
		(effects
			(font
				(size 1.27 1.27)
			)
			(justify left)
		)
		(property "Intersheetrefs" "${INTERSHEET_REFS}"
			(at 145.467 165.1 0)
			(effects
				(font
					(size 1.27 1.27)
				)
				(justify left)
			)
		)
	)
	(global_label "MSS_REFCLK_N"
		(shape input)
		(at 125.73 118.11 0)
		(fields_autoplaced yes)
		(effects
			(font
				(size 1.27 1.27)
			)
			(justify left)
		)
		(property "Intersheetrefs" "${INTERSHEET_REFS}"
			(at 142.927 118.11 0)
			(effects
				(font
					(size 1.27 1.27)
				)
				(justify left)
			)
		)
	)
	(global_label "MSS_REFCLK_P"
		(shape input)
		(at 125.73 115.57 0)
		(fields_autoplaced yes)
		(effects
			(font
				(size 1.27 1.27)
			)
			(justify left)
		)
		(property "Intersheetrefs" "${INTERSHEET_REFS}"
			(at 142.8665 115.57 0)
			(effects
				(font
					(size 1.27 1.27)
				)
				(justify left)
			)
		)
	)
	(global_label "MSS_REFCLK_P"
		(shape input)
		(at 128.27 162.56 0)
		(fields_autoplaced yes)
		(effects
			(font
				(size 1.27 1.27)
			)
			(justify left)
		)
		(property "Intersheetrefs" "${INTERSHEET_REFS}"
			(at 145.4065 162.56 0)
			(effects
				(font
					(size 1.27 1.27)
				)
				(justify left)
			)
		)
	)
	(hierarchical_label "SGMII{SGMII}"
		(shape input)
		(at 139.7 95.25 0)
		(effects
			(font
				(size 1.27 1.27)
			)
			(justify left)
		)
	)
	(hierarchical_label "LPDDR4{LPDDR4}"
		(shape input)
		(at 250.19 72.39 180)
		(effects
			(font
				(size 1.27 1.27)
			)
			(justify right)
		)
	)
	(hierarchical_label "LPDDR4{LPDDR4}"
		(shape input)
		(at 361.95 72.39 0)
		(effects
			(font
				(size 1.27 1.27)
			)
			(justify left)
		)
	)
	(symbol
		(lib_id "antmicroCapacitors0402:C_100n_0402")
		(at 78.74 167.64 90)
		(unit 1)
		(exclude_from_sim no)
		(in_bom yes)
		(on_board yes)
		(dnp no)
		(property "Reference" "C4"
			(at 81.28 163.83 90)
			(effects
				(font
					(size 1.27 1.27)
					(thickness 0.15)
				)
				(justify right)
			)
		)
		(property "Value" "C_100n_0402"
			(at 88.9 147.32 0)
			(effects
				(font
					(size 1.27 1.27)
					(thickness 0.15)
				)
				(justify left bottom)
				(hide yes)
			)
		)
		(property "Footprint" "antmicro-footprints:C_0402_1005Metric"
			(at 91.44 147.32 0)
			(effects
				(font
					(size 1.27 1.27)
					(thickness 0.15)
				)
				(justify left bottom)
				(hide yes)
			)
		)
		(property "Datasheet" "https://www.murata.com/products/productdetail?partno=GRM155R61H104KE14%23"
			(at 93.98 147.32 0)
			(effects
				(font
					(size 1.27 1.27)
					(thickness 0.15)
				)
				(justify left bottom)
				(hide yes)
			)
		)
		(property "Description" "SMD Multilayer Ceramic Capacitor, 0.1 µF, 50 V, 0402 [1005 Metric], ± 10%, X5R, GRM Series"
			(at 78.74 167.64 0)
			(effects
				(font
					(size 1.27 1.27)
				)
				(hide yes)
			)
		)
		(property "MPN" "GRM155R61H104KE14D"
			(at 96.52 147.32 0)
			(effects
				(font
					(size 1.27 1.27)
					(thickness 0.15)
				)
				(justify left bottom)
				(hide yes)
			)
		)
		(property "Manufacturer" "Murata"
			(at 99.06 147.32 0)
			(effects
				(font
					(size 1.27 1.27)
					(thickness 0.15)
				)
				(justify left bottom)
				(hide yes)
			)
		)
		(property "License" "Apache-2.0"
			(at 101.6 147.32 0)
			(effects
				(font
					(size 1.27 1.27)
					(thickness 0.15)
				)
				(justify left bottom)
				(hide yes)
			)
		)
		(property "Author" "Antmicro"
			(at 104.14 147.32 0)
			(effects
				(font
					(size 1.27 1.27)
					(thickness 0.15)
				)
				(justify left bottom)
				(hide yes)
			)
		)
		(property "Val" "100n"
			(at 86.36 166.37 90)
			(effects
				(font
					(size 1.27 1.27)
					(thickness 0.15)
				)
				(justify left bottom)
			)
		)
		(property "Voltage" "50V"
			(at 106.68 147.32 0)
			(effects
				(font
					(size 1.27 1.27)
				)
				(justify left bottom)
				(hide yes)
			)
		)
		(property "Dielectric" "X5R"
			(at 109.22 147.32 0)
			(effects
				(font
					(size 1.27 1.27)
				)
				(justify left bottom)
				(hide yes)
			)
		)
		(property "Public" ""
			(at 111.76 147.32 0)
			(effects
				(font
					(size 1.27 1.27)
				)
				(justify left bottom)
				(hide yes)
			)
		)
		(pin "1"
		)
		(pin "2"
		)
		(instances
			(project "polarfire-som"
				(path ""
					(reference "C4")
					(unit 1)
				)
			)
		)
	)
	(symbol
		(lib_id "antmicropower:+3V3")
		(at 78.74 160.02 0)
		(unit 1)
		(exclude_from_sim no)
		(in_bom yes)
		(on_board yes)
		(dnp no)
		(fields_autoplaced yes)
		(property "Reference" "#PWR0246"
			(at 93.98 162.56 0)
			(effects
				(font
					(size 1.27 1.27)
					(thickness 0.15)
				)
				(justify left bottom)
				(hide yes)
			)
		)
		(property "Value" "+3V3"
			(at 78.74 154.94 0)
			(effects
				(font
					(size 1.27 1.27)
					(thickness 0.15)
				)
			)
		)
		(property "Footprint" ""
			(at 93.98 167.64 0)
			(effects
				(font
					(size 1.27 1.27)
					(thickness 0.15)
				)
				(justify left bottom)
				(hide yes)
			)
		)
		(property "Datasheet" ""
			(at 93.98 170.18 0)
			(effects
				(font
					(size 1.27 1.27)
					(thickness 0.15)
				)
				(justify left bottom)
				(hide yes)
			)
		)
		(property "Description" ""
			(at 78.74 160.02 0)
			(effects
				(font
					(size 1.27 1.27)
				)
				(hide yes)
			)
		)
		(property "Author" "Antmicro"
			(at 93.98 167.64 0)
			(effects
				(font
					(size 1.27 1.27)
					(thickness 0.15)
				)
				(justify left bottom)
				(hide yes)
			)
		)
		(property "License" "Apache-2.0"
			(at 93.98 170.18 0)
			(effects
				(font
					(size 1.27 1.27)
					(thickness 0.15)
				)
				(justify left bottom)
				(hide yes)
			)
		)
		(pin "1"
		)
		(instances
			(project "polarfire-som"
				(path ""
					(reference "#PWR0246")
					(unit 1)
				)
			)
		)
	)
	(symbol
		(lib_id "antmicroResistors0402:R_0R_0402")
		(at 120.65 162.56 0)
		(unit 1)
		(exclude_from_sim no)
		(in_bom yes)
		(on_board yes)
		(dnp no)
		(property "Reference" "R60"
			(at 121.92 160.02 0)
			(effects
				(font
					(size 1.27 1.27)
					(thickness 0.15)
				)
			)
		)
		(property "Value" "R_0R_0402"
			(at 140.97 175.26 0)
			(effects
				(font
					(size 1.27 1.27)
					(thickness 0.15)
				)
				(justify left bottom)
				(hide yes)
			)
		)
		(property "Footprint" "antmicro-footprints:R_0402_1005Metric"
			(at 140.97 177.8 0)
			(effects
				(font
					(size 1.27 1.27)
					(thickness 0.15)
				)
				(justify left bottom)
				(hide yes)
			)
		)
		(property "Datasheet" "https://industrial.panasonic.com/cdbs/www-data/pdf/RDA0000/AOA0000C301.pdf"
			(at 140.97 180.34 0)
			(effects
				(font
					(size 1.27 1.27)
					(thickness 0.15)
				)
				(justify left bottom)
				(hide yes)
			)
		)
		(property "Description" "SMD Chip Resistor, Jumper, 0 ohm, 100 mW, 0402 [1005 Metric], Thick Film, General Purpose"
			(at 120.65 162.56 0)
			(effects
				(font
					(size 1.27 1.27)
				)
				(hide yes)
			)
		)
		(property "MPN" "ERJ2GE0R00X"
			(at 140.97 182.88 0)
			(effects
				(font
					(size 1.27 1.27)
					(thickness 0.15)
				)
				(justify left bottom)
				(hide yes)
			)
		)
		(property "Manufacturer" "Panasonic"
			(at 140.97 185.42 0)
			(effects
				(font
					(size 1.27 1.27)
					(thickness 0.15)
				)
				(justify left bottom)
				(hide yes)
			)
		)
		(property "License" "Apache-2.0"
			(at 140.97 187.96 0)
			(effects
				(font
					(size 1.27 1.27)
					(thickness 0.15)
				)
				(justify left bottom)
				(hide yes)
			)
		)
		(property "Author" "Antmicro"
			(at 140.97 190.5 0)
			(effects
				(font
					(size 1.27 1.27)
					(thickness 0.15)
				)
				(justify left bottom)
				(hide yes)
			)
		)
		(property "Val" "0R"
			(at 125.73 160.02 0)
			(effects
				(font
					(size 1.27 1.27)
					(thickness 0.15)
				)
			)
		)
		(property "Tolerance" "~"
			(at 140.97 172.72 0)
			(effects
				(font
					(size 1.27 1.27)
				)
				(justify left bottom)
				(hide yes)
			)
		)
		(property "Current" "1A"
			(at 140.97 193.04 0)
			(effects
				(font
					(size 1.27 1.27)
					(thickness 0.15)
				)
				(justify left bottom)
				(hide yes)
			)
		)
		(property "Public" ""
			(at 140.97 193.04 0)
			(effects
				(font
					(size 1.27 1.27)
				)
				(justify left bottom)
				(hide yes)
			)
		)
		(pin "1"
		)
		(pin "2"
		)
		(instances
			(project "polarfire-som"
				(path ""
					(reference "R60")
					(unit 1)
				)
			)
		)
	)
	(symbol
		(lib_id "antmicroFPGAChips:MPFS250T-FCVG484E")
		(at 74.93 100.33 0)
		(unit 6)
		(exclude_from_sim no)
		(in_bom yes)
		(on_board yes)
		(dnp no)
		(fields_autoplaced yes)
		(property "Reference" "U1"
			(at 97.79 90.17 0)
			(effects
				(font
					(size 1.27 1.27)
					(thickness 0.15)
				)
			)
		)
		(property "Value" "MPFS250T-FCVG484"
			(at 180.34 105.41 0)
			(effects
				(font
					(size 1.27 1.27)
					(thickness 0.15)
				)
				(justify left bottom)
				(hide yes)
			)
		)
		(property "Footprint" "antmicro-footprints:BGA-484_19x19mm_Layout22x22_P0.8mm_FCVG484"
			(at 180.34 107.95 0)
			(effects
				(font
					(size 1.27 1.27)
					(thickness 0.15)
				)
				(justify left bottom)
				(hide yes)
			)
		)
		(property "Datasheet" "https://ww1.microchip.com/downloads/aemDocuments/documents/FPGA/ProductDocuments/DataSheets/PolarFire-SoC-Datasheet-DS00004248.pdf"
			(at 180.34 110.49 0)
			(effects
				(font
					(size 1.27 1.27)
					(thickness 0.15)
				)
				(justify left bottom)
				(hide yes)
			)
		)
		(property "Description" "RISC-V System On Chip (SOC) IC PolarFire® FPGA - 254K Logic Modules 484-FCBGA (19x19)"
			(at 180.34 120.65 0)
			(effects
				(font
					(size 1.27 1.27)
				)
				(justify left bottom)
				(hide yes)
			)
		)
		(property "MPN" "MPFS250T-FCVG484E"
			(at 97.79 92.71 0)
			(effects
				(font
					(size 1.27 1.27)
					(thickness 0.15)
				)
			)
		)
		(property "Manufacturer" "Microchip Technology"
			(at 180.34 113.03 0)
			(effects
				(font
					(size 1.27 1.27)
					(thickness 0.15)
				)
				(justify left bottom)
				(hide yes)
			)
		)
		(property "VSD_class" "MPFS250T"
			(at 179.07 118.11 0)
			(effects
				(font
					(size 1.27 1.27)
					(thickness 0.15)
				)
				(justify left bottom)
				(hide yes)
			)
		)
		(property "Author" "Antmicro"
			(at 180.34 115.57 0)
			(effects
				(font
					(size 1.27 1.27)
					(thickness 0.15)
				)
				(justify left bottom)
				(hide yes)
			)
		)
		(property "License" "Apache-2.0"
			(at 180.34 118.11 0)
			(effects
				(font
					(size 1.27 1.27)
					(thickness 0.15)
				)
				(justify left bottom)
				(hide yes)
			)
		)
		(pin "AA12"
		)
		(pin "AA13"
		)
		(pin "AA15"
		)
		(pin "AA16"
		)
		(pin "AA17"
		)
		(pin "AA18"
		)
		(pin "AA20"
		)
		(pin "AA21"
		)
		(pin "AA22"
		)
		(pin "AB12"
		)
		(pin "AB13"
		)
		(pin "AB14"
		)
		(pin "AB15"
		)
		(pin "AB17"
		)
		(pin "AB18"
		)
		(pin "AB19"
		)
		(pin "AB20"
		)
		(pin "AB21"
		)
		(pin "R12"
		)
		(pin "R14"
		)
		(pin "R15"
		)
		(pin "R16"
		)
		(pin "T12"
		)
		(pin "T13"
		)
		(pin "T15"
		)
		(pin "T16"
		)
		(pin "T17"
		)
		(pin "U12"
		)
		(pin "U13"
		)
		(pin "U14"
		)
		(pin "U15"
		)
		(pin "U17"
		)
		(pin "U18"
		)
		(pin "U19"
		)
		(pin "V12"
		)
		(pin "V14"
		)
		(pin "V15"
		)
		(pin "V16"
		)
		(pin "V17"
		)
		(pin "V19"
		)
		(pin "V20"
		)
		(pin "V21"
		)
		(pin "V22"
		)
		(pin "W12"
		)
		(pin "W13"
		)
		(pin "W14"
		)
		(pin "W16"
		)
		(pin "W17"
		)
		(pin "W18"
		)
		(pin "W19"
		)
		(pin "W21"
		)
		(pin "W22"
		)
		(pin "Y13"
		)
		(pin "Y14"
		)
		(pin "Y15"
		)
		(pin "Y16"
		)
		(pin "Y18"
		)
		(pin "Y19"
		)
		(pin "Y20"
		)
		(pin "Y21"
		)
		(pin "A10"
		)
		(pin "A11"
		)
		(pin "A12"
		)
		(pin "A13"
		)
		(pin "A15"
		)
		(pin "A16"
		)
		(pin "A17"
		)
		(pin "A18"
		)
		(pin "A20"
		)
		(pin "A21"
		)
		(pin "A5"
		)
		(pin "A6"
		)
		(pin "A7"
		)
		(pin "A8"
		)
		(pin "B10"
		)
		(pin "B12"
		)
		(pin "B13"
		)
		(pin "B14"
		)
		(pin "B15"
		)
		(pin "B17"
		)
		(pin "B18"
		)
		(pin "B19"
		)
		(pin "B20"
		)
		(pin "B21"
		)
		(pin "B22"
		)
		(pin "B4"
		)
		(pin "B5"
		)
		(pin "B7"
		)
		(pin "B8"
		)
		(pin "B9"
		)
		(pin "C10"
		)
		(pin "C11"
		)
		(pin "C12"
		)
		(pin "C14"
		)
		(pin "C15"
		)
		(pin "C16"
		)
		(pin "C17"
		)
		(pin "C19"
		)
		(pin "C20"
		)
		(pin "C22"
		)
		(pin "C4"
		)
		(pin "C5"
		)
		(pin "C6"
		)
		(pin "C7"
		)
		(pin "C9"
		)
		(pin "D11"
		)
		(pin "D12"
		)
		(pin "D13"
		)
		(pin "D14"
		)
		(pin "D16"
		)
		(pin "D17"
		)
		(pin "D18"
		)
		(pin "D19"
		)
		(pin "D20"
		)
		(pin "D21"
		)
		(pin "D22"
		)
		(pin "D6"
		)
		(pin "D7"
		)
		(pin "D8"
		)
		(pin "D9"
		)
		(pin "E10"
		)
		(pin "E11"
		)
		(pin "E13"
		)
		(pin "E14"
		)
		(pin "E15"
		)
		(pin "E16"
		)
		(pin "E18"
		)
		(pin "E19"
		)
		(pin "F10"
		)
		(pin "F11"
		)
		(pin "F12"
		)
		(pin "F13"
		)
		(pin "F15"
		)
		(pin "F16"
		)
		(pin "F17"
		)
		(pin "G12"
		)
		(pin "G13"
		)
		(pin "G14"
		)
		(pin "G15"
		)
		(pin "G17"
		)
		(pin "H12"
		)
		(pin "H13"
		)
		(pin "H15"
		)
		(pin "H17"
		)
		(pin "A2"
		)
		(pin "A3"
		)
		(pin "B1"
		)
		(pin "B2"
		)
		(pin "B3"
		)
		(pin "C1"
		)
		(pin "C2"
		)
		(pin "D1"
		)
		(pin "D2"
		)
		(pin "D3"
		)
		(pin "D4"
		)
		(pin "E1"
		)
		(pin "E3"
		)
		(pin "E4"
		)
		(pin "E5"
		)
		(pin "F1"
		)
		(pin "F2"
		)
		(pin "F3"
		)
		(pin "F5"
		)
		(pin "F6"
		)
		(pin "G2"
		)
		(pin "G3"
		)
		(pin "G4"
		)
		(pin "G5"
		)
		(pin "E6"
		)
		(pin "E8"
		)
		(pin "E9"
		)
		(pin "F7"
		)
		(pin "F8"
		)
		(pin "G10"
		)
		(pin "G7"
		)
		(pin "G8"
		)
		(pin "G9"
		)
		(pin "H10"
		)
		(pin "H11"
		)
		(pin "H7"
		)
		(pin "H9"
		)
		(pin "H1"
		)
		(pin "H2"
		)
		(pin "H4"
		)
		(pin "H5"
		)
		(pin "H6"
		)
		(pin "J1"
		)
		(pin "J2"
		)
		(pin "J3"
		)
		(pin "J4"
		)
		(pin "J6"
		)
		(pin "J7"
		)
		(pin "K3"
		)
		(pin "K4"
		)
		(pin "K5"
		)
		(pin "K6"
		)
		(pin "K7"
		)
		(pin "L5"
		)
		(pin "L6"
		)
		(pin "L7"
		)
		(pin "L8"
		)
		(pin "M7"
		)
		(pin "N6"
		)
		(pin "N7"
		)
		(pin "N8"
		)
		(pin "AA1"
		)
		(pin "AA10"
		)
		(pin "AA11"
		)
		(pin "AA2"
		)
		(pin "AA3"
		)
		(pin "AA5"
		)
		(pin "AA6"
		)
		(pin "AA7"
		)
		(pin "AA8"
		)
		(pin "AB10"
		)
		(pin "AB2"
		)
		(pin "AB3"
		)
		(pin "AB4"
		)
		(pin "AB5"
		)
		(pin "AB7"
		)
		(pin "AB8"
		)
		(pin "AB9"
		)
		(pin "K1"
		)
		(pin "L1"
		)
		(pin "L2"
		)
		(pin "L3"
		)
		(pin "M2"
		)
		(pin "M3"
		)
		(pin "M4"
		)
		(pin "M5"
		)
		(pin "N1"
		)
		(pin "N2"
		)
		(pin "N4"
		)
		(pin "N5"
		)
		(pin "P1"
		)
		(pin "P2"
		)
		(pin "P3"
		)
		(pin "P4"
		)
		(pin "P6"
		)
		(pin "P7"
		)
		(pin "P8"
		)
		(pin "R1"
		)
		(pin "R10"
		)
		(pin "R11"
		)
		(pin "R3"
		)
		(pin "R4"
		)
		(pin "R5"
		)
		(pin "R6"
		)
		(pin "R8"
		)
		(pin "T1"
		)
		(pin "T10"
		)
		(pin "T11"
		)
		(pin "T2"
		)
		(pin "T3"
		)
		(pin "T5"
		)
		(pin "T6"
		)
		(pin "T7"
		)
		(pin "T8"
		)
		(pin "U10"
		)
		(pin "U2"
		)
		(pin "U3"
		)
		(pin "U4"
		)
		(pin "U5"
		)
		(pin "U7"
		)
		(pin "U8"
		)
		(pin "U9"
		)
		(pin "V1"
		)
		(pin "V10"
		)
		(pin "V11"
		)
		(pin "V2"
		)
		(pin "V4"
		)
		(pin "V5"
		)
		(pin "V6"
		)
		(pin "V7"
		)
		(pin "V9"
		)
		(pin "W1"
		)
		(pin "W11"
		)
		(pin "W2"
		)
		(pin "W3"
		)
		(pin "W4"
		)
		(pin "W6"
		)
		(pin "W7"
		)
		(pin "W8"
		)
		(pin "W9"
		)
		(pin "Y1"
		)
		(pin "Y10"
		)
		(pin "Y11"
		)
		(pin "Y3"
		)
		(pin "Y4"
		)
		(pin "Y5"
		)
		(pin "Y6"
		)
		(pin "Y8"
		)
		(pin "Y9"
		)
		(pin "F21"
		)
		(pin "F22"
		)
		(pin "G19"
		)
		(pin "G20"
		)
		(pin "H21"
		)
		(pin "H22"
		)
		(pin "J19"
		)
		(pin "J20"
		)
		(pin "K21"
		)
		(pin "K22"
		)
		(pin "L19"
		)
		(pin "L20"
		)
		(pin "M21"
		)
		(pin "M22"
		)
		(pin "N19"
		)
		(pin "N20"
		)
		(pin "P21"
		)
		(pin "P22"
		)
		(pin "R19"
		)
		(pin "R20"
		)
		(pin "T21"
		)
		(pin "T22"
		)
		(pin "A1"
		)
		(pin "A14"
		)
		(pin "A19"
		)
		(pin "A22"
		)
		(pin "A4"
		)
		(pin "A9"
		)
		(pin "AA14"
		)
		(pin "AA19"
		)
		(pin "AA4"
		)
		(pin "AA9"
		)
		(pin "AB1"
		)
		(pin "AB11"
		)
		(pin "AB16"
		)
		(pin "AB22"
		)
		(pin "AB6"
		)
		(pin "B11"
		)
		(pin "B16"
		)
		(pin "B6"
		)
		(pin "C13"
		)
		(pin "C18"
		)
		(pin "C21"
		)
		(pin "C3"
		)
		(pin "C8"
		)
		(pin "D10"
		)
		(pin "D15"
		)
		(pin "D5"
		)
		(pin "E12"
		)
		(pin "E17"
		)
		(pin "E2"
		)
		(pin "E20"
		)
		(pin "E21"
		)
		(pin "E22"
		)
		(pin "E7"
		)
		(pin "F14"
		)
		(pin "F18"
		)
		(pin "F19"
		)
		(pin "F20"
		)
		(pin "F4"
		)
		(pin "F9"
		)
		(pin "G1"
		)
		(pin "G11"
		)
		(pin "G16"
		)
		(pin "G18"
		)
		(pin "G21"
		)
		(pin "G22"
		)
		(pin "G6"
		)
		(pin "H14"
		)
		(pin "H16"
		)
		(pin "H18"
		)
		(pin "H19"
		)
		(pin "H20"
		)
		(pin "H3"
		)
		(pin "H8"
		)
		(pin "J10"
		)
		(pin "J11"
		)
		(pin "J12"
		)
		(pin "J13"
		)
		(pin "J14"
		)
		(pin "J15"
		)
		(pin "J16"
		)
		(pin "J17"
		)
		(pin "J18"
		)
		(pin "J21"
		)
		(pin "J22"
		)
		(pin "J5"
		)
		(pin "J8"
		)
		(pin "J9"
		)
		(pin "K10"
		)
		(pin "K11"
		)
		(pin "K12"
		)
		(pin "K13"
		)
		(pin "K14"
		)
		(pin "K15"
		)
		(pin "K16"
		)
		(pin "K17"
		)
		(pin "K18"
		)
		(pin "K19"
		)
		(pin "K2"
		)
		(pin "K20"
		)
		(pin "K8"
		)
		(pin "K9"
		)
		(pin "L10"
		)
		(pin "L11"
		)
		(pin "L12"
		)
		(pin "L13"
		)
		(pin "L14"
		)
		(pin "L15"
		)
		(pin "L16"
		)
		(pin "L17"
		)
		(pin "L18"
		)
		(pin "L21"
		)
		(pin "L22"
		)
		(pin "L4"
		)
		(pin "L9"
		)
		(pin "M1"
		)
		(pin "M10"
		)
		(pin "M11"
		)
		(pin "M12"
		)
		(pin "M13"
		)
		(pin "M14"
		)
		(pin "M15"
		)
		(pin "M16"
		)
		(pin "M17"
		)
		(pin "M18"
		)
		(pin "M19"
		)
		(pin "M20"
		)
		(pin "M6"
		)
		(pin "M8"
		)
		(pin "M9"
		)
		(pin "N10"
		)
		(pin "N11"
		)
		(pin "N12"
		)
		(pin "N13"
		)
		(pin "N14"
		)
		(pin "N15"
		)
		(pin "N16"
		)
		(pin "N17"
		)
		(pin "N18"
		)
		(pin "N21"
		)
		(pin "N22"
		)
		(pin "N3"
		)
		(pin "N9"
		)
		(pin "P10"
		)
		(pin "P11"
		)
		(pin "P12"
		)
		(pin "P13"
		)
		(pin "P14"
		)
		(pin "P15"
		)
		(pin "P16"
		)
		(pin "P17"
		)
		(pin "P18"
		)
		(pin "P19"
		)
		(pin "P20"
		)
		(pin "P5"
		)
		(pin "P9"
		)
		(pin "R13"
		)
		(pin "R17"
		)
		(pin "R18"
		)
		(pin "R2"
		)
		(pin "R21"
		)
		(pin "R22"
		)
		(pin "R7"
		)
		(pin "R9"
		)
		(pin "T14"
		)
		(pin "T18"
		)
		(pin "T19"
		)
		(pin "T20"
		)
		(pin "T4"
		)
		(pin "T9"
		)
		(pin "U1"
		)
		(pin "U11"
		)
		(pin "U16"
		)
		(pin "U20"
		)
		(pin "U21"
		)
		(pin "U22"
		)
		(pin "U6"
		)
		(pin "V13"
		)
		(pin "V18"
		)
		(pin "V3"
		)
		(pin "V8"
		)
		(pin "W10"
		)
		(pin "W15"
		)
		(pin "W20"
		)
		(pin "W5"
		)
		(pin "Y12"
		)
		(pin "Y17"
		)
		(pin "Y2"
		)
		(pin "Y22"
		)
		(pin "Y7"
		)
		(instances
			(project "polarfire-som"
				(path ""
					(reference "U1")
					(unit 6)
				)
			)
		)
	)
	(symbol
		(lib_id "antmicropower:GND")
		(at 356.87 218.44 0)
		(unit 1)
		(exclude_from_sim no)
		(in_bom yes)
		(on_board yes)
		(dnp no)
		(fields_autoplaced yes)
		(property "Reference" "#PWR0125"
			(at 365.76 220.98 0)
			(effects
				(font
					(size 1.27 1.27)
					(thickness 0.15)
				)
				(justify left bottom)
				(hide yes)
			)
		)
		(property "Value" "GND"
			(at 356.87 222.885 0)
			(effects
				(font
					(size 1.27 1.27)
					(thickness 0.15)
				)
			)
		)
		(property "Footprint" ""
			(at 365.76 226.06 0)
			(effects
				(font
					(size 1.27 1.27)
					(thickness 0.15)
				)
				(justify left bottom)
				(hide yes)
			)
		)
		(property "Datasheet" ""
			(at 365.76 231.14 0)
			(effects
				(font
					(size 1.27 1.27)
					(thickness 0.15)
				)
				(justify left bottom)
				(hide yes)
			)
		)
		(property "Description" ""
			(at 356.87 218.44 0)
			(effects
				(font
					(size 1.27 1.27)
				)
				(hide yes)
			)
		)
		(property "Author" "Antmicro"
			(at 365.76 226.06 0)
			(effects
				(font
					(size 1.27 1.27)
					(thickness 0.15)
				)
				(justify left bottom)
				(hide yes)
			)
		)
		(property "License" "Apache-2.0"
			(at 365.76 228.6 0)
			(effects
				(font
					(size 1.27 1.27)
					(thickness 0.15)
				)
				(justify left bottom)
				(hide yes)
			)
		)
		(pin "1"
		)
		(instances
			(project "polarfire-som"
				(path ""
					(reference "#PWR0125")
					(unit 1)
				)
			)
		)
	)
	(symbol
		(lib_id "antmicroResistors0402:R_1k_0402")
		(at 350.52 214.63 180)
		(unit 1)
		(exclude_from_sim no)
		(in_bom yes)
		(on_board yes)
		(dnp no)
		(property "Reference" "R74"
			(at 344.17 213.36 0)
			(effects
				(font
					(size 1.27 1.27)
					(thickness 0.15)
				)
			)
		)
		(property "Value" "R_1k_0402"
			(at 330.2 201.93 0)
			(effects
				(font
					(size 1.27 1.27)
					(thickness 0.15)
				)
				(justify left bottom)
				(hide yes)
			)
		)
		(property "Footprint" "antmicro-footprints:R_0402_1005Metric"
			(at 330.2 199.39 0)
			(effects
				(font
					(size 1.27 1.27)
					(thickness 0.15)
				)
				(justify left bottom)
				(hide yes)
			)
		)
		(property "Datasheet" "https://www.bourns.com/docs/product-datasheets/cr.pdf"
			(at 330.2 196.85 0)
			(effects
				(font
					(size 1.27 1.27)
					(thickness 0.15)
				)
				(justify left bottom)
				(hide yes)
			)
		)
		(property "Description" "SMD Chip Resistor, 1 kohm, ± 1%, 63 mW, 0402 [1005 Metric], Thick Film, General Purpose"
			(at 350.52 214.63 0)
			(effects
				(font
					(size 1.27 1.27)
				)
				(hide yes)
			)
		)
		(property "MPN" "CR0402-FX-1001GLF"
			(at 330.2 194.31 0)
			(effects
				(font
					(size 1.27 1.27)
					(thickness 0.15)
				)
				(justify left bottom)
				(hide yes)
			)
		)
		(property "Manufacturer" "Bourns"
			(at 330.2 191.77 0)
			(effects
				(font
					(size 1.27 1.27)
					(thickness 0.15)
				)
				(justify left bottom)
				(hide yes)
			)
		)
		(property "License" "Apache-2.0"
			(at 330.2 189.23 0)
			(effects
				(font
					(size 1.27 1.27)
					(thickness 0.15)
				)
				(justify left bottom)
				(hide yes)
			)
		)
		(property "Author" "Antmicro"
			(at 330.2 186.69 0)
			(effects
				(font
					(size 1.27 1.27)
					(thickness 0.15)
				)
				(justify left bottom)
				(hide yes)
			)
		)
		(property "Val" "1k"
			(at 351.79 213.36 0)
			(effects
				(font
					(size 1.27 1.27)
					(thickness 0.15)
				)
			)
		)
		(property "Tolerance" "1%"
			(at 330.2 204.47 0)
			(effects
				(font
					(size 1.27 1.27)
				)
				(justify left bottom)
				(hide yes)
			)
		)
		(property "Public" ""
			(at 330.2 184.15 0)
			(effects
				(font
					(size 1.27 1.27)
				)
				(justify left bottom)
				(hide yes)
			)
		)
		(pin "1"
		)
		(pin "2"
		)
		(instances
			(project "polarfire-som"
				(path ""
					(reference "R74")
					(unit 1)
				)
			)
		)
	)
	(symbol
		(lib_id "antmicroResistors0402:R_0R_0402")
		(at 120.65 165.1 0)
		(mirror x)
		(unit 1)
		(exclude_from_sim no)
		(in_bom yes)
		(on_board yes)
		(dnp no)
		(property "Reference" "R87"
			(at 121.92 167.64 0)
			(effects
				(font
					(size 1.27 1.27)
					(thickness 0.15)
				)
			)
		)
		(property "Value" "R_0R_0402"
			(at 140.97 152.4 0)
			(effects
				(font
					(size 1.27 1.27)
					(thickness 0.15)
				)
				(justify left bottom)
				(hide yes)
			)
		)
		(property "Footprint" "antmicro-footprints:R_0402_1005Metric"
			(at 140.97 149.86 0)
			(effects
				(font
					(size 1.27 1.27)
					(thickness 0.15)
				)
				(justify left bottom)
				(hide yes)
			)
		)
		(property "Datasheet" "https://industrial.panasonic.com/cdbs/www-data/pdf/RDA0000/AOA0000C301.pdf"
			(at 140.97 147.32 0)
			(effects
				(font
					(size 1.27 1.27)
					(thickness 0.15)
				)
				(justify left bottom)
				(hide yes)
			)
		)
		(property "Description" "SMD Chip Resistor, Jumper, 0 ohm, 100 mW, 0402 [1005 Metric], Thick Film, General Purpose"
			(at 120.65 165.1 0)
			(effects
				(font
					(size 1.27 1.27)
				)
				(hide yes)
			)
		)
		(property "MPN" "ERJ2GE0R00X"
			(at 140.97 144.78 0)
			(effects
				(font
					(size 1.27 1.27)
					(thickness 0.15)
				)
				(justify left bottom)
				(hide yes)
			)
		)
		(property "Manufacturer" "Panasonic"
			(at 140.97 142.24 0)
			(effects
				(font
					(size 1.27 1.27)
					(thickness 0.15)
				)
				(justify left bottom)
				(hide yes)
			)
		)
		(property "License" "Apache-2.0"
			(at 140.97 139.7 0)
			(effects
				(font
					(size 1.27 1.27)
					(thickness 0.15)
				)
				(justify left bottom)
				(hide yes)
			)
		)
		(property "Author" "Antmicro"
			(at 140.97 137.16 0)
			(effects
				(font
					(size 1.27 1.27)
					(thickness 0.15)
				)
				(justify left bottom)
				(hide yes)
			)
		)
		(property "Val" "0R"
			(at 125.73 167.64 0)
			(effects
				(font
					(size 1.27 1.27)
					(thickness 0.15)
				)
			)
		)
		(property "Tolerance" "~"
			(at 140.97 154.94 0)
			(effects
				(font
					(size 1.27 1.27)
				)
				(justify left bottom)
				(hide yes)
			)
		)
		(property "Current" "1A"
			(at 140.97 134.62 0)
			(effects
				(font
					(size 1.27 1.27)
					(thickness 0.15)
				)
				(justify left bottom)
				(hide yes)
			)
		)
		(property "Public" ""
			(at 140.97 134.62 0)
			(effects
				(font
					(size 1.27 1.27)
				)
				(justify left bottom)
				(hide yes)
			)
		)
		(pin "1"
		)
		(pin "2"
		)
		(instances
			(project "polarfire-som"
				(path ""
					(reference "R87")
					(unit 1)
				)
			)
		)
	)
	(symbol
		(lib_id "antmicroFPGAChips:MPFS250T-FCVG484E")
		(at 273.05 77.47 0)
		(unit 7)
		(exclude_from_sim no)
		(in_bom yes)
		(on_board yes)
		(dnp no)
		(fields_autoplaced yes)
		(property "Reference" "U1"
			(at 304.8 67.31 0)
			(effects
				(font
					(size 1.27 1.27)
					(thickness 0.15)
				)
			)
		)
		(property "Value" "MPFS250T-FCVG484"
			(at 378.46 82.55 0)
			(effects
				(font
					(size 1.27 1.27)
					(thickness 0.15)
				)
				(justify left bottom)
				(hide yes)
			)
		)
		(property "Footprint" "antmicro-footprints:BGA-484_19x19mm_Layout22x22_P0.8mm_FCVG484"
			(at 378.46 85.09 0)
			(effects
				(font
					(size 1.27 1.27)
					(thickness 0.15)
				)
				(justify left bottom)
				(hide yes)
			)
		)
		(property "Datasheet" "https://ww1.microchip.com/downloads/aemDocuments/documents/FPGA/ProductDocuments/DataSheets/PolarFire-SoC-Datasheet-DS00004248.pdf"
			(at 378.46 87.63 0)
			(effects
				(font
					(size 1.27 1.27)
					(thickness 0.15)
				)
				(justify left bottom)
				(hide yes)
			)
		)
		(property "Description" "RISC-V System On Chip (SOC) IC PolarFire® FPGA - 254K Logic Modules 484-FCBGA (19x19)"
			(at 378.46 97.79 0)
			(effects
				(font
					(size 1.27 1.27)
				)
				(justify left bottom)
				(hide yes)
			)
		)
		(property "MPN" "MPFS250T-FCVG484E"
			(at 304.8 69.85 0)
			(effects
				(font
					(size 1.27 1.27)
					(thickness 0.15)
				)
			)
		)
		(property "Manufacturer" "Microchip Technology"
			(at 378.46 90.17 0)
			(effects
				(font
					(size 1.27 1.27)
					(thickness 0.15)
				)
				(justify left bottom)
				(hide yes)
			)
		)
		(property "VSD_class" "MPFS250T"
			(at 377.19 95.25 0)
			(effects
				(font
					(size 1.27 1.27)
					(thickness 0.15)
				)
				(justify left bottom)
				(hide yes)
			)
		)
		(property "Author" "Antmicro"
			(at 378.46 92.71 0)
			(effects
				(font
					(size 1.27 1.27)
					(thickness 0.15)
				)
				(justify left bottom)
				(hide yes)
			)
		)
		(property "License" "Apache-2.0"
			(at 378.46 95.25 0)
			(effects
				(font
					(size 1.27 1.27)
					(thickness 0.15)
				)
				(justify left bottom)
				(hide yes)
			)
		)
		(pin "AA12"
		)
		(pin "AA13"
		)
		(pin "AA15"
		)
		(pin "AA16"
		)
		(pin "AA17"
		)
		(pin "AA18"
		)
		(pin "AA20"
		)
		(pin "AA21"
		)
		(pin "AA22"
		)
		(pin "AB12"
		)
		(pin "AB13"
		)
		(pin "AB14"
		)
		(pin "AB15"
		)
		(pin "AB17"
		)
		(pin "AB18"
		)
		(pin "AB19"
		)
		(pin "AB20"
		)
		(pin "AB21"
		)
		(pin "R12"
		)
		(pin "R14"
		)
		(pin "R15"
		)
		(pin "R16"
		)
		(pin "T12"
		)
		(pin "T13"
		)
		(pin "T15"
		)
		(pin "T16"
		)
		(pin "T17"
		)
		(pin "U12"
		)
		(pin "U13"
		)
		(pin "U14"
		)
		(pin "U15"
		)
		(pin "U17"
		)
		(pin "U18"
		)
		(pin "U19"
		)
		(pin "V12"
		)
		(pin "V14"
		)
		(pin "V15"
		)
		(pin "V16"
		)
		(pin "V17"
		)
		(pin "V19"
		)
		(pin "V20"
		)
		(pin "V21"
		)
		(pin "V22"
		)
		(pin "W12"
		)
		(pin "W13"
		)
		(pin "W14"
		)
		(pin "W16"
		)
		(pin "W17"
		)
		(pin "W18"
		)
		(pin "W19"
		)
		(pin "W21"
		)
		(pin "W22"
		)
		(pin "Y13"
		)
		(pin "Y14"
		)
		(pin "Y15"
		)
		(pin "Y16"
		)
		(pin "Y18"
		)
		(pin "Y19"
		)
		(pin "Y20"
		)
		(pin "Y21"
		)
		(pin "A10"
		)
		(pin "A11"
		)
		(pin "A12"
		)
		(pin "A13"
		)
		(pin "A15"
		)
		(pin "A16"
		)
		(pin "A17"
		)
		(pin "A18"
		)
		(pin "A20"
		)
		(pin "A21"
		)
		(pin "A5"
		)
		(pin "A6"
		)
		(pin "A7"
		)
		(pin "A8"
		)
		(pin "B10"
		)
		(pin "B12"
		)
		(pin "B13"
		)
		(pin "B14"
		)
		(pin "B15"
		)
		(pin "B17"
		)
		(pin "B18"
		)
		(pin "B19"
		)
		(pin "B20"
		)
		(pin "B21"
		)
		(pin "B22"
		)
		(pin "B4"
		)
		(pin "B5"
		)
		(pin "B7"
		)
		(pin "B8"
		)
		(pin "B9"
		)
		(pin "C10"
		)
		(pin "C11"
		)
		(pin "C12"
		)
		(pin "C14"
		)
		(pin "C15"
		)
		(pin "C16"
		)
		(pin "C17"
		)
		(pin "C19"
		)
		(pin "C20"
		)
		(pin "C22"
		)
		(pin "C4"
		)
		(pin "C5"
		)
		(pin "C6"
		)
		(pin "C7"
		)
		(pin "C9"
		)
		(pin "D11"
		)
		(pin "D12"
		)
		(pin "D13"
		)
		(pin "D14"
		)
		(pin "D16"
		)
		(pin "D17"
		)
		(pin "D18"
		)
		(pin "D19"
		)
		(pin "D20"
		)
		(pin "D21"
		)
		(pin "D22"
		)
		(pin "D6"
		)
		(pin "D7"
		)
		(pin "D8"
		)
		(pin "D9"
		)
		(pin "E10"
		)
		(pin "E11"
		)
		(pin "E13"
		)
		(pin "E14"
		)
		(pin "E15"
		)
		(pin "E16"
		)
		(pin "E18"
		)
		(pin "E19"
		)
		(pin "F10"
		)
		(pin "F11"
		)
		(pin "F12"
		)
		(pin "F13"
		)
		(pin "F15"
		)
		(pin "F16"
		)
		(pin "F17"
		)
		(pin "G12"
		)
		(pin "G13"
		)
		(pin "G14"
		)
		(pin "G15"
		)
		(pin "G17"
		)
		(pin "H12"
		)
		(pin "H13"
		)
		(pin "H15"
		)
		(pin "H17"
		)
		(pin "A2"
		)
		(pin "A3"
		)
		(pin "B1"
		)
		(pin "B2"
		)
		(pin "B3"
		)
		(pin "C1"
		)
		(pin "C2"
		)
		(pin "D1"
		)
		(pin "D2"
		)
		(pin "D3"
		)
		(pin "D4"
		)
		(pin "E1"
		)
		(pin "E3"
		)
		(pin "E4"
		)
		(pin "E5"
		)
		(pin "F1"
		)
		(pin "F2"
		)
		(pin "F3"
		)
		(pin "F5"
		)
		(pin "F6"
		)
		(pin "G2"
		)
		(pin "G3"
		)
		(pin "G4"
		)
		(pin "G5"
		)
		(pin "E6"
		)
		(pin "E8"
		)
		(pin "E9"
		)
		(pin "F7"
		)
		(pin "F8"
		)
		(pin "G10"
		)
		(pin "G7"
		)
		(pin "G8"
		)
		(pin "G9"
		)
		(pin "H10"
		)
		(pin "H11"
		)
		(pin "H7"
		)
		(pin "H9"
		)
		(pin "H1"
		)
		(pin "H2"
		)
		(pin "H4"
		)
		(pin "H5"
		)
		(pin "H6"
		)
		(pin "J1"
		)
		(pin "J2"
		)
		(pin "J3"
		)
		(pin "J4"
		)
		(pin "J6"
		)
		(pin "J7"
		)
		(pin "K3"
		)
		(pin "K4"
		)
		(pin "K5"
		)
		(pin "K6"
		)
		(pin "K7"
		)
		(pin "L5"
		)
		(pin "L6"
		)
		(pin "L7"
		)
		(pin "L8"
		)
		(pin "M7"
		)
		(pin "N6"
		)
		(pin "N7"
		)
		(pin "N8"
		)
		(pin "AA1"
		)
		(pin "AA10"
		)
		(pin "AA11"
		)
		(pin "AA2"
		)
		(pin "AA3"
		)
		(pin "AA5"
		)
		(pin "AA6"
		)
		(pin "AA7"
		)
		(pin "AA8"
		)
		(pin "AB10"
		)
		(pin "AB2"
		)
		(pin "AB3"
		)
		(pin "AB4"
		)
		(pin "AB5"
		)
		(pin "AB7"
		)
		(pin "AB8"
		)
		(pin "AB9"
		)
		(pin "K1"
		)
		(pin "L1"
		)
		(pin "L2"
		)
		(pin "L3"
		)
		(pin "M2"
		)
		(pin "M3"
		)
		(pin "M4"
		)
		(pin "M5"
		)
		(pin "N1"
		)
		(pin "N2"
		)
		(pin "N4"
		)
		(pin "N5"
		)
		(pin "P1"
		)
		(pin "P2"
		)
		(pin "P3"
		)
		(pin "P4"
		)
		(pin "P6"
		)
		(pin "P7"
		)
		(pin "P8"
		)
		(pin "R1"
		)
		(pin "R10"
		)
		(pin "R11"
		)
		(pin "R3"
		)
		(pin "R4"
		)
		(pin "R5"
		)
		(pin "R6"
		)
		(pin "R8"
		)
		(pin "T1"
		)
		(pin "T10"
		)
		(pin "T11"
		)
		(pin "T2"
		)
		(pin "T3"
		)
		(pin "T5"
		)
		(pin "T6"
		)
		(pin "T7"
		)
		(pin "T8"
		)
		(pin "U10"
		)
		(pin "U2"
		)
		(pin "U3"
		)
		(pin "U4"
		)
		(pin "U5"
		)
		(pin "U7"
		)
		(pin "U8"
		)
		(pin "U9"
		)
		(pin "V1"
		)
		(pin "V10"
		)
		(pin "V11"
		)
		(pin "V2"
		)
		(pin "V4"
		)
		(pin "V5"
		)
		(pin "V6"
		)
		(pin "V7"
		)
		(pin "V9"
		)
		(pin "W1"
		)
		(pin "W11"
		)
		(pin "W2"
		)
		(pin "W3"
		)
		(pin "W4"
		)
		(pin "W6"
		)
		(pin "W7"
		)
		(pin "W8"
		)
		(pin "W9"
		)
		(pin "Y1"
		)
		(pin "Y10"
		)
		(pin "Y11"
		)
		(pin "Y3"
		)
		(pin "Y4"
		)
		(pin "Y5"
		)
		(pin "Y6"
		)
		(pin "Y8"
		)
		(pin "Y9"
		)
		(pin "F21"
		)
		(pin "F22"
		)
		(pin "G19"
		)
		(pin "G20"
		)
		(pin "H21"
		)
		(pin "H22"
		)
		(pin "J19"
		)
		(pin "J20"
		)
		(pin "K21"
		)
		(pin "K22"
		)
		(pin "L19"
		)
		(pin "L20"
		)
		(pin "M21"
		)
		(pin "M22"
		)
		(pin "N19"
		)
		(pin "N20"
		)
		(pin "P21"
		)
		(pin "P22"
		)
		(pin "R19"
		)
		(pin "R20"
		)
		(pin "T21"
		)
		(pin "T22"
		)
		(pin "A1"
		)
		(pin "A14"
		)
		(pin "A19"
		)
		(pin "A22"
		)
		(pin "A4"
		)
		(pin "A9"
		)
		(pin "AA14"
		)
		(pin "AA19"
		)
		(pin "AA4"
		)
		(pin "AA9"
		)
		(pin "AB1"
		)
		(pin "AB11"
		)
		(pin "AB16"
		)
		(pin "AB22"
		)
		(pin "AB6"
		)
		(pin "B11"
		)
		(pin "B16"
		)
		(pin "B6"
		)
		(pin "C13"
		)
		(pin "C18"
		)
		(pin "C21"
		)
		(pin "C3"
		)
		(pin "C8"
		)
		(pin "D10"
		)
		(pin "D15"
		)
		(pin "D5"
		)
		(pin "E12"
		)
		(pin "E17"
		)
		(pin "E2"
		)
		(pin "E20"
		)
		(pin "E21"
		)
		(pin "E22"
		)
		(pin "E7"
		)
		(pin "F14"
		)
		(pin "F18"
		)
		(pin "F19"
		)
		(pin "F20"
		)
		(pin "F4"
		)
		(pin "F9"
		)
		(pin "G1"
		)
		(pin "G11"
		)
		(pin "G16"
		)
		(pin "G18"
		)
		(pin "G21"
		)
		(pin "G22"
		)
		(pin "G6"
		)
		(pin "H14"
		)
		(pin "H16"
		)
		(pin "H18"
		)
		(pin "H19"
		)
		(pin "H20"
		)
		(pin "H3"
		)
		(pin "H8"
		)
		(pin "J10"
		)
		(pin "J11"
		)
		(pin "J12"
		)
		(pin "J13"
		)
		(pin "J14"
		)
		(pin "J15"
		)
		(pin "J16"
		)
		(pin "J17"
		)
		(pin "J18"
		)
		(pin "J21"
		)
		(pin "J22"
		)
		(pin "J5"
		)
		(pin "J8"
		)
		(pin "J9"
		)
		(pin "K10"
		)
		(pin "K11"
		)
		(pin "K12"
		)
		(pin "K13"
		)
		(pin "K14"
		)
		(pin "K15"
		)
		(pin "K16"
		)
		(pin "K17"
		)
		(pin "K18"
		)
		(pin "K19"
		)
		(pin "K2"
		)
		(pin "K20"
		)
		(pin "K8"
		)
		(pin "K9"
		)
		(pin "L10"
		)
		(pin "L11"
		)
		(pin "L12"
		)
		(pin "L13"
		)
		(pin "L14"
		)
		(pin "L15"
		)
		(pin "L16"
		)
		(pin "L17"
		)
		(pin "L18"
		)
		(pin "L21"
		)
		(pin "L22"
		)
		(pin "L4"
		)
		(pin "L9"
		)
		(pin "M1"
		)
		(pin "M10"
		)
		(pin "M11"
		)
		(pin "M12"
		)
		(pin "M13"
		)
		(pin "M14"
		)
		(pin "M15"
		)
		(pin "M16"
		)
		(pin "M17"
		)
		(pin "M18"
		)
		(pin "M19"
		)
		(pin "M20"
		)
		(pin "M6"
		)
		(pin "M8"
		)
		(pin "M9"
		)
		(pin "N10"
		)
		(pin "N11"
		)
		(pin "N12"
		)
		(pin "N13"
		)
		(pin "N14"
		)
		(pin "N15"
		)
		(pin "N16"
		)
		(pin "N17"
		)
		(pin "N18"
		)
		(pin "N21"
		)
		(pin "N22"
		)
		(pin "N3"
		)
		(pin "N9"
		)
		(pin "P10"
		)
		(pin "P11"
		)
		(pin "P12"
		)
		(pin "P13"
		)
		(pin "P14"
		)
		(pin "P15"
		)
		(pin "P16"
		)
		(pin "P17"
		)
		(pin "P18"
		)
		(pin "P19"
		)
		(pin "P20"
		)
		(pin "P5"
		)
		(pin "P9"
		)
		(pin "R13"
		)
		(pin "R17"
		)
		(pin "R18"
		)
		(pin "R2"
		)
		(pin "R21"
		)
		(pin "R22"
		)
		(pin "R7"
		)
		(pin "R9"
		)
		(pin "T14"
		)
		(pin "T18"
		)
		(pin "T19"
		)
		(pin "T20"
		)
		(pin "T4"
		)
		(pin "T9"
		)
		(pin "U1"
		)
		(pin "U11"
		)
		(pin "U16"
		)
		(pin "U20"
		)
		(pin "U21"
		)
		(pin "U22"
		)
		(pin "U6"
		)
		(pin "V13"
		)
		(pin "V18"
		)
		(pin "V3"
		)
		(pin "V8"
		)
		(pin "W10"
		)
		(pin "W15"
		)
		(pin "W20"
		)
		(pin "W5"
		)
		(pin "Y12"
		)
		(pin "Y17"
		)
		(pin "Y2"
		)
		(pin "Y22"
		)
		(pin "Y7"
		)
		(instances
			(project "polarfire-som"
				(path ""
					(reference "U1")
					(unit 7)
				)
			)
		)
	)
	(symbol
		(lib_id "antmicropower:GND")
		(at 78.74 170.18 0)
		(unit 1)
		(exclude_from_sim no)
		(in_bom yes)
		(on_board yes)
		(dnp no)
		(property "Reference" "#PWR0247"
			(at 87.63 172.72 0)
			(effects
				(font
					(size 1.27 1.27)
					(thickness 0.15)
				)
				(justify left bottom)
				(hide yes)
			)
		)
		(property "Value" "GND"
			(at 78.74 173.99 0)
			(effects
				(font
					(size 1.27 1.27)
					(thickness 0.15)
				)
			)
		)
		(property "Footprint" ""
			(at 87.63 177.8 0)
			(effects
				(font
					(size 1.27 1.27)
					(thickness 0.15)
				)
				(justify left bottom)
				(hide yes)
			)
		)
		(property "Datasheet" ""
			(at 87.63 182.88 0)
			(effects
				(font
					(size 1.27 1.27)
					(thickness 0.15)
				)
				(justify left bottom)
				(hide yes)
			)
		)
		(property "Description" ""
			(at 78.74 170.18 0)
			(effects
				(font
					(size 1.27 1.27)
				)
				(hide yes)
			)
		)
		(property "Author" "Antmicro"
			(at 87.63 177.8 0)
			(effects
				(font
					(size 1.27 1.27)
					(thickness 0.15)
				)
				(justify left bottom)
				(hide yes)
			)
		)
		(property "License" "Apache-2.0"
			(at 87.63 180.34 0)
			(effects
				(font
					(size 1.27 1.27)
					(thickness 0.15)
				)
				(justify left bottom)
				(hide yes)
			)
		)
		(pin "1"
		)
		(instances
			(project "polarfire-som"
				(path ""
					(reference "#PWR0247")
					(unit 1)
				)
			)
		)
	)
	(symbol
		(lib_id "antmicropower:+1V1")
		(at 356.87 214.63 270)
		(unit 1)
		(exclude_from_sim no)
		(in_bom yes)
		(on_board yes)
		(dnp no)
		(property "Reference" "#PWR0113"
			(at 353.06 214.63 0)
			(effects
				(font
					(size 1.27 1.27)
				)
				(hide yes)
			)
		)
		(property "Value" "+1V1"
			(at 361.95 214.63 90)
			(effects
				(font
					(size 1.27 1.27)
				)
			)
		)
		(property "Footprint" ""
			(at 356.87 214.63 0)
			(effects
				(font
					(size 1.27 1.27)
				)
				(hide yes)
			)
		)
		(property "Datasheet" ""
			(at 356.87 214.63 0)
			(effects
				(font
					(size 1.27 1.27)
				)
				(hide yes)
			)
		)
		(property "Description" ""
			(at 356.87 214.63 0)
			(effects
				(font
					(size 1.27 1.27)
				)
				(hide yes)
			)
		)
		(pin "1"
		)
		(instances
			(project "polarfire-som"
				(path ""
					(reference "#PWR0113")
					(unit 1)
				)
			)
		)
	)
	(symbol
		(lib_id "antmicroResistors0402:R_1k_0402")
		(at 350.52 218.44 180)
		(unit 1)
		(exclude_from_sim no)
		(in_bom yes)
		(on_board yes)
		(dnp no)
		(property "Reference" "R75"
			(at 344.17 217.17 0)
			(effects
				(font
					(size 1.27 1.27)
					(thickness 0.15)
				)
			)
		)
		(property "Value" "R_1k_0402"
			(at 330.2 205.74 0)
			(effects
				(font
					(size 1.27 1.27)
					(thickness 0.15)
				)
				(justify left bottom)
				(hide yes)
			)
		)
		(property "Footprint" "antmicro-footprints:R_0402_1005Metric"
			(at 330.2 203.2 0)
			(effects
				(font
					(size 1.27 1.27)
					(thickness 0.15)
				)
				(justify left bottom)
				(hide yes)
			)
		)
		(property "Datasheet" "https://www.bourns.com/docs/product-datasheets/cr.pdf"
			(at 330.2 200.66 0)
			(effects
				(font
					(size 1.27 1.27)
					(thickness 0.15)
				)
				(justify left bottom)
				(hide yes)
			)
		)
		(property "Description" "SMD Chip Resistor, 1 kohm, ± 1%, 63 mW, 0402 [1005 Metric], Thick Film, General Purpose"
			(at 350.52 218.44 0)
			(effects
				(font
					(size 1.27 1.27)
				)
				(hide yes)
			)
		)
		(property "MPN" "CR0402-FX-1001GLF"
			(at 330.2 198.12 0)
			(effects
				(font
					(size 1.27 1.27)
					(thickness 0.15)
				)
				(justify left bottom)
				(hide yes)
			)
		)
		(property "Manufacturer" "Bourns"
			(at 330.2 195.58 0)
			(effects
				(font
					(size 1.27 1.27)
					(thickness 0.15)
				)
				(justify left bottom)
				(hide yes)
			)
		)
		(property "License" "Apache-2.0"
			(at 330.2 193.04 0)
			(effects
				(font
					(size 1.27 1.27)
					(thickness 0.15)
				)
				(justify left bottom)
				(hide yes)
			)
		)
		(property "Author" "Antmicro"
			(at 330.2 190.5 0)
			(effects
				(font
					(size 1.27 1.27)
					(thickness 0.15)
				)
				(justify left bottom)
				(hide yes)
			)
		)
		(property "Val" "1k"
			(at 351.79 217.17 0)
			(effects
				(font
					(size 1.27 1.27)
					(thickness 0.15)
				)
			)
		)
		(property "Tolerance" "1%"
			(at 330.2 208.28 0)
			(effects
				(font
					(size 1.27 1.27)
				)
				(justify left bottom)
				(hide yes)
			)
		)
		(property "Public" ""
			(at 330.2 187.96 0)
			(effects
				(font
					(size 1.27 1.27)
				)
				(justify left bottom)
				(hide yes)
			)
		)
		(pin "1"
		)
		(pin "2"
		)
		(instances
			(project "polarfire-som"
				(path ""
					(reference "R75")
					(unit 1)
				)
			)
		)
	)
	(symbol
		(lib_id "antmicroOscillators:Oscillator_125MHz_DSC1103DI2")
		(at 88.9 162.56 0)
		(unit 1)
		(exclude_from_sim no)
		(in_bom yes)
		(on_board yes)
		(dnp no)
		(fields_autoplaced yes)
		(property "Reference" "Y3"
			(at 98.425 152.4 0)
			(effects
				(font
					(size 1.27 1.27)
					(thickness 0.15)
				)
			)
		)
		(property "Value" "Oscillator_125MHz_DSC1103DI2"
			(at 117.475 174.625 0)
			(effects
				(font
					(size 1.27 1.27)
					(thickness 0.15)
				)
				(justify left bottom)
				(hide yes)
			)
		)
		(property "Footprint" "antmicro-footprints:Oscillator_SMD_Microchip_DSC1103DI2_2.5x2x0.85mm"
			(at 117.475 177.165 0)
			(effects
				(font
					(size 1.27 1.27)
					(thickness 0.15)
				)
				(justify left bottom)
				(hide yes)
			)
		)
		(property "Datasheet" "https://ww1.microchip.com/downloads/aemDocuments/documents/TCG/ProductDocuments/DataSheets/DSC1103-23-Low-Jitter-Precision-LVDS-Oscillator-DS20005745C.pdf"
			(at 117.475 179.705 0)
			(effects
				(font
					(size 1.27 1.27)
					(thickness 0.15)
				)
				(justify left bottom)
				(hide yes)
			)
		)
		(property "Description" "125 MHz XO (Standard) LVDS Oscillator 3.3V Enable/Disable 6-SMD, No Lead"
			(at 88.9 162.56 0)
			(effects
				(font
					(size 1.27 1.27)
				)
				(hide yes)
			)
		)
		(property "Manufacturer" "Microchip Technology"
			(at 117.475 167.005 0)
			(effects
				(font
					(size 1.27 1.27)
					(thickness 0.15)
				)
				(justify left bottom)
				(hide yes)
			)
		)
		(property "MPN" "DSC1103DI2-125.0000"
			(at 98.425 154.94 0)
			(effects
				(font
					(size 1.27 1.27)
					(thickness 0.15)
				)
			)
		)
		(property "Val" "125 MHz"
			(at 98.425 157.48 0)
			(effects
				(font
					(size 1.27 1.27)
					(thickness 0.15)
				)
			)
		)
		(property "Author" "Antmicro"
			(at 117.475 182.245 0)
			(effects
				(font
					(size 1.27 1.27)
					(thickness 0.15)
				)
				(justify left bottom)
				(hide yes)
			)
		)
		(property "License" "Apache-2.0"
			(at 117.475 184.785 0)
			(effects
				(font
					(size 1.27 1.27)
					(thickness 0.15)
				)
				(justify left bottom)
				(hide yes)
			)
		)
		(property "Public" ""
			(at 123.19 186.69 0)
			(effects
				(font
					(size 1.27 1.27)
				)
				(justify left bottom)
				(hide yes)
			)
		)
		(pin "6"
		)
		(pin "3"
		)
		(pin "2"
		)
		(pin "1"
		)
		(pin "5"
		)
		(pin "4"
		)
		(instances
			(project "polarfire-som"
				(path ""
					(reference "Y3")
					(unit 1)
				)
			)
		)
	)
)
